FILE_TYPE = MACRO_DRAWING;
SET COLOR_WIRE YELLOW;
SET COLOR_PROP MONO;
SET COLOR_DOT WHITE;
SET COLOR_ARC YELLOW;
SET COLOR_BODY GREEN;
SET COLOR_NOTE MONO;
SET PROP_DISPLAY VALUE;
SET PAGE_NUMBER P79;
FORCEADD OFFPAGE..3
(1550 5150);
FORCEPROP 2 LAST $XR0 58 
J 0
(1764 5150);
DISPLAY 0.638298 (1764 5150);
PAINT MONO (1764 5150);
FORCEPROP 2 LAST $XR1 80 
J 0
(1854 5150);
DISPLAY 0.638298 (1854 5150);
PAINT MONO (1854 5150);
FORCEPROP 2 LAST CDS_LIB mstr_standard
J 0
(1550 5150);
DISPLAY 0.787234 (1550 5150);
PAINT MONO (1550 5150);
DISPLAY INVISIBLE (1550 5150);
FORCEPROP 1 LAST OFFPAGE TRUE
J 0
(1875 5025);
DISPLAY 0.936170 (1875 5025);
PAINT GREEN (1875 5025);
DISPLAY INVISIBLE (1875 5025);
FORCEPROP 1 LAST COMMENT_BODY TRUE
J 0
(1500 5050);
DISPLAY 0.936170 (1500 5050);
PAINT GREEN (1500 5050);
DISPLAY INVISIBLE (1500 5050);
FORCEPROP 2 LAST PATH I1
J 0
(1750 5225);
DISPLAY 0.787234 (1750 5225);
PAINT MONO (1750 5225);
DISPLAY INVISIBLE (1750 5225);
FORCEADD TAP..6
R 2
(650 4950);
FORCEPROP 3 LASTPIN (600 4950) SIG_NAME M_H_DQS_DP<15>
J 0
(610 4960);
DISPLAY 0.659574 (610 4960);
PAINT MONO (610 4960);
DISPLAY INVISIBLE (610 4960);
FORCEPROP 1 LASTPIN (600 4950) BN 15
J 2
(650 4960);
DISPLAY 0.617021 (650 4960);
PAINT PINK (650 4960);
FORCEPROP 2 LAST CDS_LIB mstr_standard
J 0
(650 4950);
DISPLAY 0.787234 (650 4950);
PAINT MONO (650 4950);
DISPLAY INVISIBLE (650 4950);
FORCEPROP 1 LAST BODY_TYPE PLUMBING
J 2
(650 4900);
DISPLAY 1.234043 (650 4900);
PAINT GREEN (650 4900);
DISPLAY INVISIBLE (650 4900);
FORCEPROP 1 LAST HDL_TAP TRUE
J 2
(325 4825);
DISPLAY 1.234043 (325 4825);
PAINT GREEN (325 4825);
DISPLAY INVISIBLE (325 4825);
FORCEPROP 1 LAST PATH I10
J 2
(650 4950);
DISPLAY 0.936170 (650 4950);
PAINT GREEN (650 4950);
DISPLAY INVISIBLE (650 4950);
FORCEADD TAP..6
R 2
(-1850 2000);
FORCEPROP 3 LASTPIN (-1900 2000) SIG_NAME M_H_DQ<4>
J 0
(-1890 2010);
DISPLAY 0.659574 (-1890 2010);
PAINT MONO (-1890 2010);
DISPLAY INVISIBLE (-1890 2010);
FORCEPROP 1 LASTPIN (-1900 2000) BN 4
J 2
(-1850 2010);
DISPLAY 0.617021 (-1850 2010);
PAINT PINK (-1850 2010);
FORCEPROP 2 LAST CDS_LIB mstr_standard
J 2
(-1850 2000);
DISPLAY 0.787234 (-1850 2000);
PAINT MONO (-1850 2000);
DISPLAY INVISIBLE (-1850 2000);
FORCEPROP 1 LAST BODY_TYPE PLUMBING
J 2
(-1850 1950);
DISPLAY 1.234043 (-1850 1950);
PAINT GREEN (-1850 1950);
DISPLAY INVISIBLE (-1850 1950);
FORCEPROP 1 LAST HDL_TAP TRUE
J 2
(-2175 1875);
DISPLAY 1.234043 (-2175 1875);
PAINT GREEN (-2175 1875);
DISPLAY INVISIBLE (-2175 1875);
FORCEPROP 1 LAST PATH I100
J 2
(-1850 2000);
DISPLAY 0.936170 (-1850 2000);
PAINT GREEN (-1850 2000);
DISPLAY INVISIBLE (-1850 2000);
FORCEADD TAP..6
R 2
(-1850 2100);
FORCEPROP 3 LASTPIN (-1900 2100) SIG_NAME M_H_DQ<6>
J 0
(-1890 2110);
DISPLAY 0.659574 (-1890 2110);
PAINT MONO (-1890 2110);
DISPLAY INVISIBLE (-1890 2110);
FORCEPROP 1 LASTPIN (-1900 2100) BN 6
J 2
(-1850 2110);
DISPLAY 0.617021 (-1850 2110);
PAINT PINK (-1850 2110);
FORCEPROP 2 LAST CDS_LIB mstr_standard
J 2
(-1850 2100);
DISPLAY 0.787234 (-1850 2100);
PAINT MONO (-1850 2100);
DISPLAY INVISIBLE (-1850 2100);
FORCEPROP 1 LAST BODY_TYPE PLUMBING
J 2
(-1850 2050);
DISPLAY 1.234043 (-1850 2050);
PAINT GREEN (-1850 2050);
DISPLAY INVISIBLE (-1850 2050);
FORCEPROP 1 LAST HDL_TAP TRUE
J 2
(-2175 1975);
DISPLAY 1.234043 (-2175 1975);
PAINT GREEN (-2175 1975);
DISPLAY INVISIBLE (-2175 1975);
FORCEPROP 1 LAST PATH I101
J 2
(-1850 2100);
DISPLAY 0.936170 (-1850 2100);
PAINT GREEN (-1850 2100);
DISPLAY INVISIBLE (-1850 2100);
FORCEADD TAP..6
R 2
(-1850 2050);
FORCEPROP 3 LASTPIN (-1900 2050) SIG_NAME M_H_DQ<7>
J 0
(-1890 2060);
DISPLAY 0.659574 (-1890 2060);
PAINT MONO (-1890 2060);
DISPLAY INVISIBLE (-1890 2060);
FORCEPROP 1 LASTPIN (-1900 2050) BN 7
J 2
(-1850 2060);
DISPLAY 0.617021 (-1850 2060);
PAINT PINK (-1850 2060);
FORCEPROP 2 LAST CDS_LIB mstr_standard
J 2
(-1850 2050);
DISPLAY 0.787234 (-1850 2050);
PAINT MONO (-1850 2050);
DISPLAY INVISIBLE (-1850 2050);
FORCEPROP 1 LAST BODY_TYPE PLUMBING
J 2
(-1850 2000);
DISPLAY 1.234043 (-1850 2000);
PAINT GREEN (-1850 2000);
DISPLAY INVISIBLE (-1850 2000);
FORCEPROP 1 LAST HDL_TAP TRUE
J 2
(-2175 1925);
DISPLAY 1.234043 (-2175 1925);
PAINT GREEN (-2175 1925);
DISPLAY INVISIBLE (-2175 1925);
FORCEPROP 1 LAST PATH I102
J 2
(-1850 2050);
DISPLAY 0.936170 (-1850 2050);
PAINT GREEN (-1850 2050);
DISPLAY INVISIBLE (-1850 2050);
FORCEADD TAP..6
R 2
(-1850 2150);
FORCEPROP 3 LASTPIN (-1900 2150) SIG_NAME M_H_DQ<9>
J 0
(-1890 2160);
DISPLAY 0.659574 (-1890 2160);
PAINT MONO (-1890 2160);
DISPLAY INVISIBLE (-1890 2160);
FORCEPROP 1 LASTPIN (-1900 2150) BN 9
J 2
(-1850 2160);
DISPLAY 0.617021 (-1850 2160);
PAINT PINK (-1850 2160);
FORCEPROP 2 LAST CDS_LIB mstr_standard
J 2
(-1850 2150);
DISPLAY 0.787234 (-1850 2150);
PAINT MONO (-1850 2150);
DISPLAY INVISIBLE (-1850 2150);
FORCEPROP 1 LAST BODY_TYPE PLUMBING
J 2
(-1850 2100);
DISPLAY 1.234043 (-1850 2100);
PAINT GREEN (-1850 2100);
DISPLAY INVISIBLE (-1850 2100);
FORCEPROP 1 LAST HDL_TAP TRUE
J 2
(-2175 2025);
DISPLAY 1.234043 (-2175 2025);
PAINT GREEN (-2175 2025);
DISPLAY INVISIBLE (-2175 2025);
FORCEPROP 1 LAST PATH I103
J 2
(-1850 2150);
DISPLAY 0.936170 (-1850 2150);
PAINT GREEN (-1850 2150);
DISPLAY INVISIBLE (-1850 2150);
FORCEADD TAP..6
R 2
(-1850 2200);
FORCEPROP 3 LASTPIN (-1900 2200) SIG_NAME M_H_DQ<8>
J 0
(-1890 2210);
DISPLAY 0.659574 (-1890 2210);
PAINT MONO (-1890 2210);
DISPLAY INVISIBLE (-1890 2210);
FORCEPROP 1 LASTPIN (-1900 2200) BN 8
J 2
(-1850 2210);
DISPLAY 0.617021 (-1850 2210);
PAINT PINK (-1850 2210);
FORCEPROP 2 LAST CDS_LIB mstr_standard
J 2
(-1850 2200);
DISPLAY 0.787234 (-1850 2200);
PAINT MONO (-1850 2200);
DISPLAY INVISIBLE (-1850 2200);
FORCEPROP 1 LAST BODY_TYPE PLUMBING
J 2
(-1850 2150);
DISPLAY 1.234043 (-1850 2150);
PAINT GREEN (-1850 2150);
DISPLAY INVISIBLE (-1850 2150);
FORCEPROP 1 LAST HDL_TAP TRUE
J 2
(-2175 2075);
DISPLAY 1.234043 (-2175 2075);
PAINT GREEN (-2175 2075);
DISPLAY INVISIBLE (-2175 2075);
FORCEPROP 1 LAST PATH I104
J 2
(-1850 2200);
DISPLAY 0.936170 (-1850 2200);
PAINT GREEN (-1850 2200);
DISPLAY INVISIBLE (-1850 2200);
FORCEADD TAP..6
R 2
(-1850 2250);
FORCEPROP 3 LASTPIN (-1900 2250) SIG_NAME M_H_DQ<11>
J 0
(-1890 2260);
DISPLAY 0.659574 (-1890 2260);
PAINT MONO (-1890 2260);
DISPLAY INVISIBLE (-1890 2260);
FORCEPROP 1 LASTPIN (-1900 2250) BN 11
J 2
(-1850 2260);
DISPLAY 0.617021 (-1850 2260);
PAINT PINK (-1850 2260);
FORCEPROP 2 LAST CDS_LIB mstr_standard
J 2
(-1850 2250);
DISPLAY 0.787234 (-1850 2250);
PAINT MONO (-1850 2250);
DISPLAY INVISIBLE (-1850 2250);
FORCEPROP 1 LAST BODY_TYPE PLUMBING
J 2
(-1850 2200);
DISPLAY 1.234043 (-1850 2200);
PAINT GREEN (-1850 2200);
DISPLAY INVISIBLE (-1850 2200);
FORCEPROP 1 LAST HDL_TAP TRUE
J 2
(-2175 2125);
DISPLAY 1.234043 (-2175 2125);
PAINT GREEN (-2175 2125);
DISPLAY INVISIBLE (-2175 2125);
FORCEPROP 1 LAST PATH I105
J 2
(-1850 2250);
DISPLAY 0.936170 (-1850 2250);
PAINT GREEN (-1850 2250);
DISPLAY INVISIBLE (-1850 2250);
FORCEADD TAP..6
R 2
(-1850 1900);
FORCEPROP 3 LASTPIN (-1900 1900) SIG_NAME M_H_DQ<2>
J 0
(-1890 1910);
DISPLAY 0.659574 (-1890 1910);
PAINT MONO (-1890 1910);
DISPLAY INVISIBLE (-1890 1910);
FORCEPROP 1 LASTPIN (-1900 1900) BN 2
J 2
(-1850 1910);
DISPLAY 0.617021 (-1850 1910);
PAINT PINK (-1850 1910);
FORCEPROP 2 LAST CDS_LIB mstr_standard
J 2
(-1850 1900);
DISPLAY 0.787234 (-1850 1900);
PAINT MONO (-1850 1900);
DISPLAY INVISIBLE (-1850 1900);
FORCEPROP 1 LAST BODY_TYPE PLUMBING
J 2
(-1850 1850);
DISPLAY 1.234043 (-1850 1850);
PAINT GREEN (-1850 1850);
DISPLAY INVISIBLE (-1850 1850);
FORCEPROP 1 LAST HDL_TAP TRUE
J 2
(-2175 1775);
DISPLAY 1.234043 (-2175 1775);
PAINT GREEN (-2175 1775);
DISPLAY INVISIBLE (-2175 1775);
FORCEPROP 1 LAST PATH I106
J 2
(-1850 1900);
DISPLAY 0.936170 (-1850 1900);
PAINT GREEN (-1850 1900);
DISPLAY INVISIBLE (-1850 1900);
FORCEADD TAP..6
R 2
(-1850 1950);
FORCEPROP 3 LASTPIN (-1900 1950) SIG_NAME M_H_DQ<5>
J 0
(-1890 1960);
DISPLAY 0.659574 (-1890 1960);
PAINT MONO (-1890 1960);
DISPLAY INVISIBLE (-1890 1960);
FORCEPROP 1 LASTPIN (-1900 1950) BN 5
J 2
(-1850 1960);
DISPLAY 0.617021 (-1850 1960);
PAINT PINK (-1850 1960);
FORCEPROP 2 LAST CDS_LIB mstr_standard
J 2
(-1850 1950);
DISPLAY 0.787234 (-1850 1950);
PAINT MONO (-1850 1950);
DISPLAY INVISIBLE (-1850 1950);
FORCEPROP 1 LAST BODY_TYPE PLUMBING
J 2
(-1850 1900);
DISPLAY 1.234043 (-1850 1900);
PAINT GREEN (-1850 1900);
DISPLAY INVISIBLE (-1850 1900);
FORCEPROP 1 LAST HDL_TAP TRUE
J 2
(-2175 1825);
DISPLAY 1.234043 (-2175 1825);
PAINT GREEN (-2175 1825);
DISPLAY INVISIBLE (-2175 1825);
FORCEPROP 1 LAST PATH I107
J 2
(-1850 1950);
DISPLAY 0.936170 (-1850 1950);
PAINT GREEN (-1850 1950);
DISPLAY INVISIBLE (-1850 1950);
FORCEADD TAP..6
R 2
(-1850 1800);
FORCEPROP 3 LASTPIN (-1900 1800) SIG_NAME M_H_DQ<0>
J 0
(-1890 1810);
DISPLAY 0.659574 (-1890 1810);
PAINT MONO (-1890 1810);
DISPLAY INVISIBLE (-1890 1810);
FORCEPROP 1 LASTPIN (-1900 1800) BN 0
J 2
(-1850 1810);
DISPLAY 0.617021 (-1850 1810);
PAINT PINK (-1850 1810);
FORCEPROP 2 LAST CDS_LIB mstr_standard
J 2
(-1850 1800);
DISPLAY 0.787234 (-1850 1800);
PAINT MONO (-1850 1800);
DISPLAY INVISIBLE (-1850 1800);
FORCEPROP 1 LAST BODY_TYPE PLUMBING
J 2
(-1850 1750);
DISPLAY 1.234043 (-1850 1750);
PAINT GREEN (-1850 1750);
DISPLAY INVISIBLE (-1850 1750);
FORCEPROP 1 LAST HDL_TAP TRUE
J 2
(-2175 1675);
DISPLAY 1.234043 (-2175 1675);
PAINT GREEN (-2175 1675);
DISPLAY INVISIBLE (-2175 1675);
FORCEPROP 1 LAST PATH I108
J 2
(-1850 1800);
DISPLAY 0.936170 (-1850 1800);
PAINT GREEN (-1850 1800);
DISPLAY INVISIBLE (-1850 1800);
FORCEADD TAP..6
R 2
(-1850 1750);
FORCEPROP 3 LASTPIN (-1900 1750) SIG_NAME M_H_DQ<1>
J 0
(-1890 1760);
DISPLAY 0.659574 (-1890 1760);
PAINT MONO (-1890 1760);
DISPLAY INVISIBLE (-1890 1760);
FORCEPROP 1 LASTPIN (-1900 1750) BN 1
J 2
(-1850 1760);
DISPLAY 0.617021 (-1850 1760);
PAINT PINK (-1850 1760);
FORCEPROP 2 LAST CDS_LIB mstr_standard
J 2
(-1850 1750);
DISPLAY 0.787234 (-1850 1750);
PAINT MONO (-1850 1750);
DISPLAY INVISIBLE (-1850 1750);
FORCEPROP 1 LAST BODY_TYPE PLUMBING
J 2
(-1850 1700);
DISPLAY 1.234043 (-1850 1700);
PAINT GREEN (-1850 1700);
DISPLAY INVISIBLE (-1850 1700);
FORCEPROP 1 LAST HDL_TAP TRUE
J 2
(-2175 1625);
DISPLAY 1.234043 (-2175 1625);
PAINT GREEN (-2175 1625);
DISPLAY INVISIBLE (-2175 1625);
FORCEPROP 1 LAST PATH I109
J 2
(-1850 1750);
DISPLAY 0.936170 (-1850 1750);
PAINT GREEN (-1850 1750);
DISPLAY INVISIBLE (-1850 1750);
FORCEADD TAP..6
R 2
(650 4850);
FORCEPROP 3 LASTPIN (600 4850) SIG_NAME M_H_DQS_DP<14>
J 0
(610 4860);
DISPLAY 0.659574 (610 4860);
PAINT MONO (610 4860);
DISPLAY INVISIBLE (610 4860);
FORCEPROP 1 LASTPIN (600 4850) BN 14
J 2
(650 4860);
DISPLAY 0.617021 (650 4860);
PAINT PINK (650 4860);
FORCEPROP 2 LAST CDS_LIB mstr_standard
J 0
(650 4850);
DISPLAY 0.787234 (650 4850);
PAINT MONO (650 4850);
DISPLAY INVISIBLE (650 4850);
FORCEPROP 1 LAST BODY_TYPE PLUMBING
J 2
(650 4800);
DISPLAY 1.234043 (650 4800);
PAINT GREEN (650 4800);
DISPLAY INVISIBLE (650 4800);
FORCEPROP 1 LAST HDL_TAP TRUE
J 2
(325 4725);
DISPLAY 1.234043 (325 4725);
PAINT GREEN (325 4725);
DISPLAY INVISIBLE (325 4725);
FORCEPROP 1 LAST PATH I11
J 2
(650 4850);
DISPLAY 0.936170 (650 4850);
PAINT GREEN (650 4850);
DISPLAY INVISIBLE (650 4850);
FORCEADD TAP..6
R 2
(-1850 1850);
FORCEPROP 3 LASTPIN (-1900 1850) SIG_NAME M_H_DQ<3>
J 0
(-1890 1860);
DISPLAY 0.659574 (-1890 1860);
PAINT MONO (-1890 1860);
DISPLAY INVISIBLE (-1890 1860);
FORCEPROP 1 LASTPIN (-1900 1850) BN 3
J 2
(-1850 1860);
DISPLAY 0.617021 (-1850 1860);
PAINT PINK (-1850 1860);
FORCEPROP 2 LAST CDS_LIB mstr_standard
J 2
(-1850 1850);
DISPLAY 0.787234 (-1850 1850);
PAINT MONO (-1850 1850);
DISPLAY INVISIBLE (-1850 1850);
FORCEPROP 1 LAST BODY_TYPE PLUMBING
J 2
(-1850 1800);
DISPLAY 1.234043 (-1850 1800);
PAINT GREEN (-1850 1800);
DISPLAY INVISIBLE (-1850 1800);
FORCEPROP 1 LAST HDL_TAP TRUE
J 2
(-2175 1725);
DISPLAY 1.234043 (-2175 1725);
PAINT GREEN (-2175 1725);
DISPLAY INVISIBLE (-2175 1725);
FORCEPROP 1 LAST PATH I110
J 2
(-1850 1850);
DISPLAY 0.936170 (-1850 1850);
PAINT GREEN (-1850 1850);
DISPLAY INVISIBLE (-1850 1850);
FORCEADD SCONN288_H44441004..1
(-2600 3250);
FORCEPROP 1 LAST LOCATION J1G2
J 0
(-3050 5150);
DISPLAY 0.617021 (-3050 5150);
PAINT AQUA (-3050 5150);
FORCEPROP 1 LAST PART_NUMBER H44441-004
J 0
(-3050 1250);
DISPLAY 0.617021 (-3050 1250);
PAINT BLUE (-3050 1250);
FORCEPROP 1 LAST MATERIAL SCONN
J 0
(-3050 5100);
DISPLAY 0.617021 (-3050 5100);
PAINT SKYBLUE (-3050 5100);
FORCEPROP 2 LASTPIN (-3100 1750) $PN 146
J 2
(-3110 1760);
DISPLAY 0.617021 (-3110 1760);
PAINT ORANGE (-3110 1760);
FORCEPROP 2 LASTPIN (-3100 2100) $PN 284
J 2
(-3110 2110);
DISPLAY 0.617021 (-3110 2110);
PAINT ORANGE (-3110 2110);
FORCEPROP 2 LASTPIN (-3100 1900) $PN 285
J 2
(-3110 1910);
DISPLAY 0.617021 (-3110 1910);
PAINT ORANGE (-3110 1910);
FORCEPROP 2 LASTPIN (-3100 1850) $PN 141
J 2
(-3110 1860);
DISPLAY 0.617021 (-3110 1860);
PAINT ORANGE (-3110 1860);
FORCEPROP 2 LASTPIN (-3100 1450) $PN 230
J 2
(-3110 1460);
DISPLAY 0.617021 (-3110 1460);
PAINT ORANGE (-3110 1460);
FORCEPROP 2 LASTPIN (-3100 2050) $PN 238
J 2
(-3110 2060);
DISPLAY 0.617021 (-3110 2060);
PAINT ORANGE (-3110 2060);
FORCEPROP 2 LASTPIN (-3100 2000) $PN 140
J 2
(-3110 2010);
DISPLAY 0.617021 (-3110 2010);
PAINT ORANGE (-3110 2010);
FORCEPROP 2 LASTPIN (-3100 1950) $PN 139
J 2
(-3110 1960);
DISPLAY 0.617021 (-3110 1960);
PAINT ORANGE (-3110 1960);
FORCEPROP 2 LASTPIN (-3100 3400) $PN 237
J 2
(-3110 3410);
DISPLAY 0.617021 (-3110 3410);
PAINT ORANGE (-3110 3410);
FORCEPROP 2 LASTPIN (-3100 3350) $PN 93
J 2
(-3110 3360);
DISPLAY 0.617021 (-3110 3360);
PAINT ORANGE (-3110 3360);
FORCEPROP 2 LASTPIN (-3100 3300) $PN 89
J 2
(-3110 3310);
DISPLAY 0.617021 (-3110 3310);
PAINT ORANGE (-3110 3310);
FORCEPROP 2 LASTPIN (-3100 3250) $PN 84
J 2
(-3110 3260);
DISPLAY 0.617021 (-3110 3260);
PAINT ORANGE (-3110 3260);
FORCEPROP 2 LASTPIN (-3100 1650) $PN 144
J 2
(-3110 1660);
DISPLAY 0.617021 (-3110 1660);
PAINT ORANGE (-3110 1660);
FORCEPROP 2 LASTPIN (-3100 1600) $PN 227
J 2
(-3110 1610);
DISPLAY 0.617021 (-3110 1610);
PAINT ORANGE (-3110 1610);
FORCEPROP 2 LASTPIN (-3100 1550) $PN 205
J 2
(-3110 1560);
DISPLAY 0.617021 (-3110 1560);
PAINT ORANGE (-3110 1560);
FORCEPROP 2 LASTPIN (-3100 2350) $PN 58
J 2
(-3110 2360);
DISPLAY 0.617021 (-3110 2360);
PAINT ORANGE (-3110 2360);
FORCEPROP 2 LASTPIN (-3100 2400) $PN 222
J 2
(-3110 2410);
DISPLAY 0.617021 (-3110 2410);
PAINT ORANGE (-3110 2410);
FORCEPROP 2 LASTPIN (-3100 3000) $PN 91
J 2
(-3110 3010);
DISPLAY 0.617021 (-3110 3010);
PAINT ORANGE (-3110 3010);
FORCEPROP 2 LASTPIN (-3100 2950) $PN 87
J 2
(-3110 2960);
DISPLAY 0.617021 (-3110 2960);
PAINT ORANGE (-3110 2960);
FORCEPROP 2 LASTPIN (-3100 2300) $PN 78
J 2
(-3110 2310);
DISPLAY 0.617021 (-3110 2310);
PAINT ORANGE (-3110 2310);
FORCEPROP 2 LASTPIN (-2100 4900) $PN 280
J 0
(-2090 4910);
DISPLAY 0.617021 (-2090 4910);
PAINT ORANGE (-2090 4910);
FORCEPROP 2 LASTPIN (-2100 4850) $PN 135
J 0
(-2090 4860);
DISPLAY 0.617021 (-2090 4860);
PAINT ORANGE (-2090 4860);
FORCEPROP 2 LASTPIN (-2100 4800) $PN 273
J 0
(-2090 4810);
DISPLAY 0.617021 (-2090 4810);
PAINT ORANGE (-2090 4810);
FORCEPROP 2 LASTPIN (-2100 4750) $PN 128
J 0
(-2090 4760);
DISPLAY 0.617021 (-2090 4760);
PAINT ORANGE (-2090 4760);
FORCEPROP 2 LASTPIN (-2100 4700) $PN 282
J 0
(-2090 4710);
DISPLAY 0.617021 (-2090 4710);
PAINT ORANGE (-2090 4710);
FORCEPROP 2 LASTPIN (-2100 4650) $PN 137
J 0
(-2090 4660);
DISPLAY 0.617021 (-2090 4660);
PAINT ORANGE (-2090 4660);
FORCEPROP 2 LASTPIN (-2100 4600) $PN 275
J 0
(-2090 4610);
DISPLAY 0.617021 (-2090 4610);
PAINT ORANGE (-2090 4610);
FORCEPROP 2 LASTPIN (-2100 4550) $PN 130
J 0
(-2090 4560);
DISPLAY 0.617021 (-2090 4560);
PAINT ORANGE (-2090 4560);
FORCEPROP 2 LASTPIN (-2100 4500) $PN 269
J 0
(-2090 4510);
DISPLAY 0.617021 (-2090 4510);
PAINT ORANGE (-2090 4510);
FORCEPROP 2 LASTPIN (-2100 4450) $PN 124
J 0
(-2090 4460);
DISPLAY 0.617021 (-2090 4460);
PAINT ORANGE (-2090 4460);
FORCEPROP 2 LASTPIN (-2100 4400) $PN 262
J 0
(-2090 4410);
DISPLAY 0.617021 (-2090 4410);
PAINT ORANGE (-2090 4410);
FORCEPROP 2 LASTPIN (-2100 4350) $PN 117
J 0
(-2090 4360);
DISPLAY 0.617021 (-2090 4360);
PAINT ORANGE (-2090 4360);
FORCEPROP 2 LASTPIN (-2100 4300) $PN 271
J 0
(-2090 4310);
DISPLAY 0.617021 (-2090 4310);
PAINT ORANGE (-2090 4310);
FORCEPROP 2 LASTPIN (-2100 4250) $PN 126
J 0
(-2090 4260);
DISPLAY 0.617021 (-2090 4260);
PAINT ORANGE (-2090 4260);
FORCEPROP 2 LASTPIN (-2100 4200) $PN 264
J 0
(-2090 4210);
DISPLAY 0.617021 (-2090 4210);
PAINT ORANGE (-2090 4210);
FORCEPROP 2 LASTPIN (-2100 4150) $PN 119
J 0
(-2090 4160);
DISPLAY 0.617021 (-2090 4160);
PAINT ORANGE (-2090 4160);
FORCEPROP 2 LASTPIN (-2100 4100) $PN 258
J 0
(-2090 4110);
DISPLAY 0.617021 (-2090 4110);
PAINT ORANGE (-2090 4110);
FORCEPROP 2 LASTPIN (-2100 4050) $PN 113
J 0
(-2090 4060);
DISPLAY 0.617021 (-2090 4060);
PAINT ORANGE (-2090 4060);
FORCEPROP 2 LASTPIN (-2100 4000) $PN 251
J 0
(-2090 4010);
DISPLAY 0.617021 (-2090 4010);
PAINT ORANGE (-2090 4010);
FORCEPROP 2 LASTPIN (-2100 3950) $PN 106
J 0
(-2090 3960);
DISPLAY 0.617021 (-2090 3960);
PAINT ORANGE (-2090 3960);
FORCEPROP 2 LASTPIN (-2100 3900) $PN 260
J 0
(-2090 3910);
DISPLAY 0.617021 (-2090 3910);
PAINT ORANGE (-2090 3910);
FORCEPROP 2 LASTPIN (-2100 3850) $PN 115
J 0
(-2090 3860);
DISPLAY 0.617021 (-2090 3860);
PAINT ORANGE (-2090 3860);
FORCEPROP 2 LASTPIN (-2100 3800) $PN 253
J 0
(-2090 3810);
DISPLAY 0.617021 (-2090 3810);
PAINT ORANGE (-2090 3810);
FORCEPROP 2 LASTPIN (-2100 3750) $PN 108
J 0
(-2090 3760);
DISPLAY 0.617021 (-2090 3760);
PAINT ORANGE (-2090 3760);
FORCEPROP 2 LASTPIN (-2100 3700) $PN 247
J 0
(-2090 3710);
DISPLAY 0.617021 (-2090 3710);
PAINT ORANGE (-2090 3710);
FORCEPROP 2 LASTPIN (-2100 3650) $PN 102
J 0
(-2090 3660);
DISPLAY 0.617021 (-2090 3660);
PAINT ORANGE (-2090 3660);
FORCEPROP 2 LASTPIN (-2100 3600) $PN 240
J 0
(-2090 3610);
DISPLAY 0.617021 (-2090 3610);
PAINT ORANGE (-2090 3610);
FORCEPROP 2 LASTPIN (-2100 3550) $PN 95
J 0
(-2090 3560);
DISPLAY 0.617021 (-2090 3560);
PAINT ORANGE (-2090 3560);
FORCEPROP 2 LASTPIN (-2100 3500) $PN 249
J 0
(-2090 3510);
DISPLAY 0.617021 (-2090 3510);
PAINT ORANGE (-2090 3510);
FORCEPROP 2 LASTPIN (-2100 3450) $PN 104
J 0
(-2090 3460);
DISPLAY 0.617021 (-2090 3460);
PAINT ORANGE (-2090 3460);
FORCEPROP 2 LASTPIN (-2100 3400) $PN 242
J 0
(-2090 3410);
DISPLAY 0.617021 (-2090 3410);
PAINT ORANGE (-2090 3410);
FORCEPROP 2 LASTPIN (-2100 3350) $PN 97
J 0
(-2090 3360);
DISPLAY 0.617021 (-2090 3360);
PAINT ORANGE (-2090 3360);
FORCEPROP 2 LASTPIN (-2100 3300) $PN 188
J 0
(-2090 3310);
DISPLAY 0.617021 (-2090 3310);
PAINT ORANGE (-2090 3310);
FORCEPROP 2 LASTPIN (-2100 3250) $PN 43
J 0
(-2090 3260);
DISPLAY 0.617021 (-2090 3260);
PAINT ORANGE (-2090 3260);
FORCEPROP 2 LASTPIN (-2100 3200) $PN 181
J 0
(-2090 3210);
DISPLAY 0.617021 (-2090 3210);
PAINT ORANGE (-2090 3210);
FORCEPROP 2 LASTPIN (-2100 3150) $PN 36
J 0
(-2090 3160);
DISPLAY 0.617021 (-2090 3160);
PAINT ORANGE (-2090 3160);
FORCEPROP 2 LASTPIN (-2100 3100) $PN 190
J 0
(-2090 3110);
DISPLAY 0.617021 (-2090 3110);
PAINT ORANGE (-2090 3110);
FORCEPROP 2 LASTPIN (-2100 3050) $PN 45
J 0
(-2090 3060);
DISPLAY 0.617021 (-2090 3060);
PAINT ORANGE (-2090 3060);
FORCEPROP 2 LASTPIN (-2100 3000) $PN 183
J 0
(-2090 3010);
DISPLAY 0.617021 (-2090 3010);
PAINT ORANGE (-2090 3010);
FORCEPROP 2 LASTPIN (-2100 2950) $PN 38
J 0
(-2090 2960);
DISPLAY 0.617021 (-2090 2960);
PAINT ORANGE (-2090 2960);
FORCEPROP 2 LASTPIN (-2100 2900) $PN 177
J 0
(-2090 2910);
DISPLAY 0.617021 (-2090 2910);
PAINT ORANGE (-2090 2910);
FORCEPROP 2 LASTPIN (-2100 2850) $PN 32
J 0
(-2090 2860);
DISPLAY 0.617021 (-2090 2860);
PAINT ORANGE (-2090 2860);
FORCEPROP 2 LASTPIN (-2100 2800) $PN 170
J 0
(-2090 2810);
DISPLAY 0.617021 (-2090 2810);
PAINT ORANGE (-2090 2810);
FORCEPROP 2 LASTPIN (-2100 2750) $PN 25
J 0
(-2090 2760);
DISPLAY 0.617021 (-2090 2760);
PAINT ORANGE (-2090 2760);
FORCEPROP 2 LASTPIN (-2100 2700) $PN 179
J 0
(-2090 2710);
DISPLAY 0.617021 (-2090 2710);
PAINT ORANGE (-2090 2710);
FORCEPROP 2 LASTPIN (-2100 2650) $PN 34
J 0
(-2090 2660);
DISPLAY 0.617021 (-2090 2660);
PAINT ORANGE (-2090 2660);
FORCEPROP 2 LASTPIN (-2100 2600) $PN 172
J 0
(-2090 2610);
DISPLAY 0.617021 (-2090 2610);
PAINT ORANGE (-2090 2610);
FORCEPROP 2 LASTPIN (-2100 2550) $PN 27
J 0
(-2090 2560);
DISPLAY 0.617021 (-2090 2560);
PAINT ORANGE (-2090 2560);
FORCEPROP 2 LASTPIN (-2100 2500) $PN 166
J 0
(-2090 2510);
DISPLAY 0.617021 (-2090 2510);
PAINT ORANGE (-2090 2510);
FORCEPROP 2 LASTPIN (-2100 2450) $PN 21
J 0
(-2090 2460);
DISPLAY 0.617021 (-2090 2460);
PAINT ORANGE (-2090 2460);
FORCEPROP 2 LASTPIN (-2100 2400) $PN 159
J 0
(-2090 2410);
DISPLAY 0.617021 (-2090 2410);
PAINT ORANGE (-2090 2410);
FORCEPROP 2 LASTPIN (-2100 2350) $PN 14
J 0
(-2090 2360);
DISPLAY 0.617021 (-2090 2360);
PAINT ORANGE (-2090 2360);
FORCEPROP 2 LASTPIN (-2100 2300) $PN 168
J 0
(-2090 2310);
DISPLAY 0.617021 (-2090 2310);
PAINT ORANGE (-2090 2310);
FORCEPROP 2 LASTPIN (-2100 2250) $PN 23
J 0
(-2090 2260);
DISPLAY 0.617021 (-2090 2260);
PAINT ORANGE (-2090 2260);
FORCEPROP 2 LASTPIN (-2100 2200) $PN 161
J 0
(-2090 2210);
DISPLAY 0.617021 (-2090 2210);
PAINT ORANGE (-2090 2210);
FORCEPROP 2 LASTPIN (-2100 2150) $PN 16
J 0
(-2090 2160);
DISPLAY 0.617021 (-2090 2160);
PAINT ORANGE (-2090 2160);
FORCEPROP 2 LASTPIN (-2100 2100) $PN 155
J 0
(-2090 2110);
DISPLAY 0.617021 (-2090 2110);
PAINT ORANGE (-2090 2110);
FORCEPROP 2 LASTPIN (-2100 2050) $PN 10
J 0
(-2090 2060);
DISPLAY 0.617021 (-2090 2060);
PAINT ORANGE (-2090 2060);
FORCEPROP 2 LASTPIN (-2100 2000) $PN 148
J 0
(-2090 2010);
DISPLAY 0.617021 (-2090 2010);
PAINT ORANGE (-2090 2010);
FORCEPROP 2 LASTPIN (-2100 1950) $PN 3
J 0
(-2090 1960);
DISPLAY 0.617021 (-2090 1960);
PAINT ORANGE (-2090 1960);
FORCEPROP 2 LASTPIN (-2100 1900) $PN 157
J 0
(-2090 1910);
DISPLAY 0.617021 (-2090 1910);
PAINT ORANGE (-2090 1910);
FORCEPROP 2 LASTPIN (-2100 1850) $PN 12
J 0
(-2090 1860);
DISPLAY 0.617021 (-2090 1860);
PAINT ORANGE (-2090 1860);
FORCEPROP 2 LASTPIN (-2100 1800) $PN 150
J 0
(-2090 1810);
DISPLAY 0.617021 (-2090 1810);
PAINT ORANGE (-2090 1810);
FORCEPROP 2 LASTPIN (-2100 1750) $PN 5
J 0
(-2090 1760);
DISPLAY 0.617021 (-2090 1760);
PAINT ORANGE (-2090 1760);
FORCEPROP 2 LASTPIN (-3100 3150) $PN 203
J 2
(-3110 3160);
DISPLAY 0.617021 (-3110 3160);
PAINT ORANGE (-3110 3160);
FORCEPROP 2 LASTPIN (-3100 3100) $PN 60
J 2
(-3110 3110);
DISPLAY 0.617021 (-3110 3110);
PAINT ORANGE (-3110 3110);
FORCEPROP 2 LASTPIN (-3100 3700) $PN 218
J 2
(-3110 3710);
DISPLAY 0.617021 (-3110 3710);
PAINT ORANGE (-3110 3710);
FORCEPROP 2 LASTPIN (-3100 3650) $PN 219
J 2
(-3110 3660);
DISPLAY 0.617021 (-3110 3660);
PAINT ORANGE (-3110 3660);
FORCEPROP 2 LASTPIN (-3100 3600) $PN 74
J 2
(-3110 3610);
DISPLAY 0.617021 (-3110 3610);
PAINT ORANGE (-3110 3610);
FORCEPROP 2 LASTPIN (-3100 3550) $PN 75
J 2
(-3110 3560);
DISPLAY 0.617021 (-3110 3560);
PAINT ORANGE (-3110 3560);
FORCEPROP 2 LASTPIN (-3100 2850) $PN 199
J 2
(-3110 2860);
DISPLAY 0.617021 (-3110 2860);
PAINT ORANGE (-3110 2860);
FORCEPROP 2 LASTPIN (-3100 2800) $PN 54
J 2
(-3110 2810);
DISPLAY 0.617021 (-3110 2810);
PAINT ORANGE (-3110 2810);
FORCEPROP 2 LASTPIN (-3100 2750) $PN 192
J 2
(-3110 2760);
DISPLAY 0.617021 (-3110 2760);
PAINT ORANGE (-3110 2760);
FORCEPROP 2 LASTPIN (-3100 2700) $PN 47
J 2
(-3110 2710);
DISPLAY 0.617021 (-3110 2710);
PAINT ORANGE (-3110 2710);
FORCEPROP 2 LASTPIN (-3100 2650) $PN 201
J 2
(-3110 2660);
DISPLAY 0.617021 (-3110 2660);
PAINT ORANGE (-3110 2660);
FORCEPROP 2 LASTPIN (-3100 2600) $PN 56
J 2
(-3110 2610);
DISPLAY 0.617021 (-3110 2610);
PAINT ORANGE (-3110 2610);
FORCEPROP 2 LASTPIN (-3100 2550) $PN 194
J 2
(-3110 2560);
DISPLAY 0.617021 (-3110 2560);
PAINT ORANGE (-3110 2560);
FORCEPROP 2 LASTPIN (-3100 2500) $PN 49
J 2
(-3110 2510);
DISPLAY 0.617021 (-3110 2510);
PAINT ORANGE (-3110 2510);
FORCEPROP 2 LASTPIN (-3100 3450) $PN 235
J 2
(-3110 3460);
DISPLAY 0.617021 (-3110 3460);
PAINT ORANGE (-3110 3460);
FORCEPROP 2 LASTPIN (-3100 3850) $PN 207
J 2
(-3110 3860);
DISPLAY 0.617021 (-3110 3860);
PAINT ORANGE (-3110 3860);
FORCEPROP 2 LASTPIN (-3100 3800) $PN 63
J 2
(-3110 3810);
DISPLAY 0.617021 (-3110 3810);
PAINT ORANGE (-3110 3810);
FORCEPROP 2 LASTPIN (-3100 3950) $PN 224
J 2
(-3110 3960);
DISPLAY 0.617021 (-3110 3960);
PAINT ORANGE (-3110 3960);
FORCEPROP 2 LASTPIN (-3100 3900) $PN 81
J 2
(-3110 3910);
DISPLAY 0.617021 (-3110 3910);
PAINT ORANGE (-3110 3910);
FORCEPROP 2 LASTPIN (-3100 2250) $PN 208
J 2
(-3110 2260);
DISPLAY 0.617021 (-3110 2260);
PAINT ORANGE (-3110 2260);
FORCEPROP 2 LASTPIN (-3100 2200) $PN 62
J 2
(-3110 2210);
DISPLAY 0.617021 (-3110 2210);
PAINT ORANGE (-3110 2210);
FORCEPROP 2 LASTPIN (-3100 4900) $PN 234
J 2
(-3110 4910);
DISPLAY 0.617021 (-3110 4910);
PAINT ORANGE (-3110 4910);
FORCEPROP 2 LASTPIN (-3100 4850) $PN 82
J 2
(-3110 4860);
DISPLAY 0.617021 (-3110 4860);
PAINT ORANGE (-3110 4860);
FORCEPROP 2 LASTPIN (-3100 4800) $PN 86
J 2
(-3110 4810);
DISPLAY 0.617021 (-3110 4810);
PAINT ORANGE (-3110 4810);
FORCEPROP 2 LASTPIN (-3100 4750) $PN 228
J 2
(-3110 4760);
DISPLAY 0.617021 (-3110 4760);
PAINT ORANGE (-3110 4760);
FORCEPROP 2 LASTPIN (-3100 4700) $PN 232
J 2
(-3110 4710);
DISPLAY 0.617021 (-3110 4710);
PAINT ORANGE (-3110 4710);
FORCEPROP 2 LASTPIN (-3100 4650) $PN 65
J 2
(-3110 4660);
DISPLAY 0.617021 (-3110 4660);
PAINT ORANGE (-3110 4660);
FORCEPROP 2 LASTPIN (-3100 4600) $PN 210
J 2
(-3110 4610);
DISPLAY 0.617021 (-3110 4610);
PAINT ORANGE (-3110 4610);
FORCEPROP 2 LASTPIN (-3100 4550) $PN 225
J 2
(-3110 4560);
DISPLAY 0.617021 (-3110 4560);
PAINT ORANGE (-3110 4560);
FORCEPROP 2 LASTPIN (-3100 4500) $PN 66
J 2
(-3110 4510);
DISPLAY 0.617021 (-3110 4510);
PAINT ORANGE (-3110 4510);
FORCEPROP 2 LASTPIN (-3100 4450) $PN 68
J 2
(-3110 4460);
DISPLAY 0.617021 (-3110 4460);
PAINT ORANGE (-3110 4460);
FORCEPROP 2 LASTPIN (-3100 4400) $PN 211
J 2
(-3110 4410);
DISPLAY 0.617021 (-3110 4410);
PAINT ORANGE (-3110 4410);
FORCEPROP 2 LASTPIN (-3100 4350) $PN 69
J 2
(-3110 4360);
DISPLAY 0.617021 (-3110 4360);
PAINT ORANGE (-3110 4360);
FORCEPROP 2 LASTPIN (-3100 4300) $PN 213
J 2
(-3110 4310);
DISPLAY 0.617021 (-3110 4310);
PAINT ORANGE (-3110 4310);
FORCEPROP 2 LASTPIN (-3100 4250) $PN 214
J 2
(-3110 4260);
DISPLAY 0.617021 (-3110 4260);
PAINT ORANGE (-3110 4260);
FORCEPROP 2 LASTPIN (-3100 4200) $PN 71
J 2
(-3110 4210);
DISPLAY 0.617021 (-3110 4210);
PAINT ORANGE (-3110 4210);
FORCEPROP 2 LASTPIN (-3100 4150) $PN 216
J 2
(-3110 4160);
DISPLAY 0.617021 (-3110 4160);
PAINT ORANGE (-3110 4160);
FORCEPROP 2 LASTPIN (-3100 4100) $PN 72
J 2
(-3110 4110);
DISPLAY 0.617021 (-3110 4110);
PAINT ORANGE (-3110 4110);
FORCEPROP 2 LASTPIN (-3100 4050) $PN 79
J 2
(-3110 4060);
DISPLAY 0.617021 (-3110 4060);
PAINT ORANGE (-3110 4060);
FORCEPROP 1 LAST PACK_TYPE PIP
J 0
(-3050 5200);
PAINT SKYBLUE (-3050 5200);
DISPLAY INVISIBLE (-3050 5200);
FORCEPROP 2 LAST BOM_COST MEM
J 0
(-2600 3250);
PAINT ORANGE (-2600 3250);
DISPLAY INVISIBLE (-2600 3250);
FORCEPROP 2 LAST CDS_LIB mstr_sconn
J 0
(-2600 3250);
PAINT ORANGE (-2600 3250);
DISPLAY INVISIBLE (-2600 3250);
FORCEPROP 2 LAST SEC_TYPE PIP
J 0
(-3050 5200);
DISPLAY 1.021277 (-3050 5200);
PAINT ORANGE (-3050 5200);
DISPLAY INVISIBLE (-3050 5200);
FORCEPROP 2 LAST SEC 1
J 0
(-3050 5200);
DISPLAY 0.680851 (-3050 5200);
PAINT MONO (-3050 5200);
DISPLAY INVISIBLE (-3050 5200);
FORCEPROP 2 LAST CDS_LOCATION J1G2
J 0
(-3050 5150);
DISPLAY 0.617021 (-3050 5150);
PAINT AQUA (-3050 5150);
DISPLAY INVISIBLE (-3050 5150);
FORCEPROP 1 LAST PATH I111
J 0
(-2600 5100);
PAINT GREEN (-2600 5100);
DISPLAY INVISIBLE (-2600 5100);
FORCEPROP 2 LAST ROOM DDR4_CH_H
J 0
(-2600 3250);
PAINT ORANGE (-2600 3250);
DISPLAY INVISIBLE (-2600 3250);
FORCEADD TAP..6
(-3350 4850);
FORCEPROP 3 LASTPIN (-3300 4850) SIG_NAME M_H_MA<16>
J 0
(-3290 4860);
DISPLAY 0.659574 (-3290 4860);
PAINT MONO (-3290 4860);
DISPLAY INVISIBLE (-3290 4860);
FORCEPROP 1 LASTPIN (-3300 4850) BN 16
J 0
(-3350 4860);
DISPLAY 0.617021 (-3350 4860);
PAINT PINK (-3350 4860);
FORCEPROP 2 LAST CDS_LIB mstr_standard
J 2
(-3350 4850);
DISPLAY 0.787234 (-3350 4850);
PAINT MONO (-3350 4850);
DISPLAY INVISIBLE (-3350 4850);
FORCEPROP 1 LAST BODY_TYPE PLUMBING
J 0
(-3350 4800);
DISPLAY 1.234043 (-3350 4800);
PAINT GREEN (-3350 4800);
DISPLAY INVISIBLE (-3350 4800);
FORCEPROP 1 LAST HDL_TAP TRUE
J 0
(-3025 4725);
DISPLAY 1.234043 (-3025 4725);
PAINT GREEN (-3025 4725);
DISPLAY INVISIBLE (-3025 4725);
FORCEPROP 1 LAST PATH I112
J 0
(-3350 4850);
DISPLAY 0.936170 (-3350 4850);
PAINT GREEN (-3350 4850);
DISPLAY INVISIBLE (-3350 4850);
FORCEADD TAP..6
(-3350 4900);
FORCEPROP 3 LASTPIN (-3300 4900) SIG_NAME M_H_MA<17>
J 0
(-3290 4910);
DISPLAY 0.659574 (-3290 4910);
PAINT MONO (-3290 4910);
DISPLAY INVISIBLE (-3290 4910);
FORCEPROP 1 LASTPIN (-3300 4900) BN 17
J 0
(-3350 4910);
DISPLAY 0.617021 (-3350 4910);
PAINT PINK (-3350 4910);
FORCEPROP 2 LAST CDS_LIB mstr_standard
J 0
(-3350 4900);
DISPLAY 0.787234 (-3350 4900);
PAINT MONO (-3350 4900);
DISPLAY INVISIBLE (-3350 4900);
FORCEPROP 1 LAST BODY_TYPE PLUMBING
J 0
(-3350 4850);
DISPLAY 1.234043 (-3350 4850);
PAINT GREEN (-3350 4850);
DISPLAY INVISIBLE (-3350 4850);
FORCEPROP 1 LAST HDL_TAP TRUE
J 0
(-3025 4775);
DISPLAY 1.234043 (-3025 4775);
PAINT GREEN (-3025 4775);
DISPLAY INVISIBLE (-3025 4775);
FORCEPROP 1 LAST PATH I113
J 0
(-3350 4900);
DISPLAY 0.936170 (-3350 4900);
PAINT GREEN (-3350 4900);
DISPLAY INVISIBLE (-3350 4900);
FORCEADD TAP..6
(-3350 4800);
FORCEPROP 3 LASTPIN (-3300 4800) SIG_NAME M_H_MA<15>
J 0
(-3290 4810);
DISPLAY 0.659574 (-3290 4810);
PAINT MONO (-3290 4810);
DISPLAY INVISIBLE (-3290 4810);
FORCEPROP 1 LASTPIN (-3300 4800) BN 15
J 0
(-3350 4810);
DISPLAY 0.617021 (-3350 4810);
PAINT PINK (-3350 4810);
FORCEPROP 2 LAST CDS_LIB mstr_standard
J 2
(-3350 4800);
DISPLAY 0.787234 (-3350 4800);
PAINT MONO (-3350 4800);
DISPLAY INVISIBLE (-3350 4800);
FORCEPROP 1 LAST BODY_TYPE PLUMBING
J 0
(-3350 4750);
DISPLAY 1.234043 (-3350 4750);
PAINT GREEN (-3350 4750);
DISPLAY INVISIBLE (-3350 4750);
FORCEPROP 1 LAST HDL_TAP TRUE
J 0
(-3025 4675);
DISPLAY 1.234043 (-3025 4675);
PAINT GREEN (-3025 4675);
DISPLAY INVISIBLE (-3025 4675);
FORCEPROP 1 LAST PATH I114
J 0
(-3350 4800);
DISPLAY 0.936170 (-3350 4800);
PAINT GREEN (-3350 4800);
DISPLAY INVISIBLE (-3350 4800);
FORCEADD TAP..6
(-3350 4750);
FORCEPROP 3 LASTPIN (-3300 4750) SIG_NAME M_H_MA<14>
J 0
(-3290 4760);
DISPLAY 0.659574 (-3290 4760);
PAINT MONO (-3290 4760);
DISPLAY INVISIBLE (-3290 4760);
FORCEPROP 1 LASTPIN (-3300 4750) BN 14
J 0
(-3350 4760);
DISPLAY 0.617021 (-3350 4760);
PAINT PINK (-3350 4760);
FORCEPROP 2 LAST CDS_LIB mstr_standard
J 2
(-3350 4750);
DISPLAY 0.787234 (-3350 4750);
PAINT MONO (-3350 4750);
DISPLAY INVISIBLE (-3350 4750);
FORCEPROP 1 LAST BODY_TYPE PLUMBING
J 0
(-3350 4700);
DISPLAY 1.234043 (-3350 4700);
PAINT GREEN (-3350 4700);
DISPLAY INVISIBLE (-3350 4700);
FORCEPROP 1 LAST HDL_TAP TRUE
J 0
(-3025 4625);
DISPLAY 1.234043 (-3025 4625);
PAINT GREEN (-3025 4625);
DISPLAY INVISIBLE (-3025 4625);
FORCEPROP 1 LAST PATH I115
J 0
(-3350 4750);
DISPLAY 0.936170 (-3350 4750);
PAINT GREEN (-3350 4750);
DISPLAY INVISIBLE (-3350 4750);
FORCEADD TAP..6
(-3350 4700);
FORCEPROP 3 LASTPIN (-3300 4700) SIG_NAME M_H_MA<13>
J 0
(-3290 4710);
DISPLAY 0.659574 (-3290 4710);
PAINT MONO (-3290 4710);
DISPLAY INVISIBLE (-3290 4710);
FORCEPROP 1 LASTPIN (-3300 4700) BN 13
J 0
(-3350 4710);
DISPLAY 0.617021 (-3350 4710);
PAINT PINK (-3350 4710);
FORCEPROP 2 LAST CDS_LIB mstr_standard
J 2
(-3350 4700);
DISPLAY 0.787234 (-3350 4700);
PAINT MONO (-3350 4700);
DISPLAY INVISIBLE (-3350 4700);
FORCEPROP 1 LAST BODY_TYPE PLUMBING
J 0
(-3350 4650);
DISPLAY 1.234043 (-3350 4650);
PAINT GREEN (-3350 4650);
DISPLAY INVISIBLE (-3350 4650);
FORCEPROP 1 LAST HDL_TAP TRUE
J 0
(-3025 4575);
DISPLAY 1.234043 (-3025 4575);
PAINT GREEN (-3025 4575);
DISPLAY INVISIBLE (-3025 4575);
FORCEPROP 1 LAST PATH I116
J 0
(-3350 4700);
DISPLAY 0.936170 (-3350 4700);
PAINT GREEN (-3350 4700);
DISPLAY INVISIBLE (-3350 4700);
FORCEADD TAP..6
(-3350 4600);
FORCEPROP 3 LASTPIN (-3300 4600) SIG_NAME M_H_MA<11>
J 0
(-3290 4610);
DISPLAY 0.659574 (-3290 4610);
PAINT MONO (-3290 4610);
DISPLAY INVISIBLE (-3290 4610);
FORCEPROP 1 LASTPIN (-3300 4600) BN 11
J 0
(-3350 4610);
DISPLAY 0.617021 (-3350 4610);
PAINT PINK (-3350 4610);
FORCEPROP 2 LAST CDS_LIB mstr_standard
J 2
(-3350 4600);
DISPLAY 0.787234 (-3350 4600);
PAINT MONO (-3350 4600);
DISPLAY INVISIBLE (-3350 4600);
FORCEPROP 1 LAST BODY_TYPE PLUMBING
J 0
(-3350 4550);
DISPLAY 1.234043 (-3350 4550);
PAINT GREEN (-3350 4550);
DISPLAY INVISIBLE (-3350 4550);
FORCEPROP 1 LAST HDL_TAP TRUE
J 0
(-3025 4475);
DISPLAY 1.234043 (-3025 4475);
PAINT GREEN (-3025 4475);
DISPLAY INVISIBLE (-3025 4475);
FORCEPROP 1 LAST PATH I117
J 0
(-3350 4600);
DISPLAY 0.936170 (-3350 4600);
PAINT GREEN (-3350 4600);
DISPLAY INVISIBLE (-3350 4600);
FORCEADD TAP..6
(-3350 4650);
FORCEPROP 3 LASTPIN (-3300 4650) SIG_NAME M_H_MA<12>
J 0
(-3290 4660);
DISPLAY 0.659574 (-3290 4660);
PAINT MONO (-3290 4660);
DISPLAY INVISIBLE (-3290 4660);
FORCEPROP 1 LASTPIN (-3300 4650) BN 12
J 0
(-3350 4660);
DISPLAY 0.617021 (-3350 4660);
PAINT PINK (-3350 4660);
FORCEPROP 2 LAST CDS_LIB mstr_standard
J 2
(-3350 4650);
DISPLAY 0.787234 (-3350 4650);
PAINT MONO (-3350 4650);
DISPLAY INVISIBLE (-3350 4650);
FORCEPROP 1 LAST BODY_TYPE PLUMBING
J 0
(-3350 4600);
DISPLAY 1.234043 (-3350 4600);
PAINT GREEN (-3350 4600);
DISPLAY INVISIBLE (-3350 4600);
FORCEPROP 1 LAST HDL_TAP TRUE
J 0
(-3025 4525);
DISPLAY 1.234043 (-3025 4525);
PAINT GREEN (-3025 4525);
DISPLAY INVISIBLE (-3025 4525);
FORCEPROP 1 LAST PATH I118
J 0
(-3350 4650);
DISPLAY 0.936170 (-3350 4650);
PAINT GREEN (-3350 4650);
DISPLAY INVISIBLE (-3350 4650);
FORCEADD TAP..6
(-3350 4550);
FORCEPROP 3 LASTPIN (-3300 4550) SIG_NAME M_H_MA<10>
J 0
(-3290 4560);
DISPLAY 0.659574 (-3290 4560);
PAINT MONO (-3290 4560);
DISPLAY INVISIBLE (-3290 4560);
FORCEPROP 1 LASTPIN (-3300 4550) BN 10
J 0
(-3350 4560);
DISPLAY 0.617021 (-3350 4560);
PAINT PINK (-3350 4560);
FORCEPROP 2 LAST CDS_LIB mstr_standard
J 2
(-3350 4550);
DISPLAY 0.787234 (-3350 4550);
PAINT MONO (-3350 4550);
DISPLAY INVISIBLE (-3350 4550);
FORCEPROP 1 LAST BODY_TYPE PLUMBING
J 0
(-3350 4500);
DISPLAY 1.234043 (-3350 4500);
PAINT GREEN (-3350 4500);
DISPLAY INVISIBLE (-3350 4500);
FORCEPROP 1 LAST HDL_TAP TRUE
J 0
(-3025 4425);
DISPLAY 1.234043 (-3025 4425);
PAINT GREEN (-3025 4425);
DISPLAY INVISIBLE (-3025 4425);
FORCEPROP 1 LAST PATH I119
J 0
(-3350 4550);
DISPLAY 0.936170 (-3350 4550);
PAINT GREEN (-3350 4550);
DISPLAY INVISIBLE (-3350 4550);
FORCEADD TAP..6
R 2
(650 4750);
FORCEPROP 3 LASTPIN (600 4750) SIG_NAME M_H_DQS_DP<13>
J 0
(610 4760);
DISPLAY 0.659574 (610 4760);
PAINT MONO (610 4760);
DISPLAY INVISIBLE (610 4760);
FORCEPROP 1 LASTPIN (600 4750) BN 13
J 2
(650 4760);
DISPLAY 0.617021 (650 4760);
PAINT PINK (650 4760);
FORCEPROP 2 LAST CDS_LIB mstr_standard
J 0
(650 4750);
DISPLAY 0.787234 (650 4750);
PAINT MONO (650 4750);
DISPLAY INVISIBLE (650 4750);
FORCEPROP 1 LAST BODY_TYPE PLUMBING
J 2
(650 4700);
DISPLAY 1.234043 (650 4700);
PAINT GREEN (650 4700);
DISPLAY INVISIBLE (650 4700);
FORCEPROP 1 LAST HDL_TAP TRUE
J 2
(325 4625);
DISPLAY 1.234043 (325 4625);
PAINT GREEN (325 4625);
DISPLAY INVISIBLE (325 4625);
FORCEPROP 1 LAST PATH I12
J 2
(650 4750);
DISPLAY 0.936170 (650 4750);
PAINT GREEN (650 4750);
DISPLAY INVISIBLE (650 4750);
FORCEADD TAP..6
(-3350 4500);
FORCEPROP 3 LASTPIN (-3300 4500) SIG_NAME M_H_MA<9>
J 0
(-3290 4510);
DISPLAY 0.659574 (-3290 4510);
PAINT MONO (-3290 4510);
DISPLAY INVISIBLE (-3290 4510);
FORCEPROP 1 LASTPIN (-3300 4500) BN 9
J 0
(-3350 4510);
DISPLAY 0.617021 (-3350 4510);
PAINT PINK (-3350 4510);
FORCEPROP 2 LAST CDS_LIB mstr_standard
J 2
(-3350 4500);
DISPLAY 0.787234 (-3350 4500);
PAINT MONO (-3350 4500);
DISPLAY INVISIBLE (-3350 4500);
FORCEPROP 1 LAST BODY_TYPE PLUMBING
J 0
(-3350 4450);
DISPLAY 1.234043 (-3350 4450);
PAINT GREEN (-3350 4450);
DISPLAY INVISIBLE (-3350 4450);
FORCEPROP 1 LAST HDL_TAP TRUE
J 0
(-3025 4375);
DISPLAY 1.234043 (-3025 4375);
PAINT GREEN (-3025 4375);
DISPLAY INVISIBLE (-3025 4375);
FORCEPROP 1 LAST PATH I120
J 0
(-3350 4500);
DISPLAY 0.936170 (-3350 4500);
PAINT GREEN (-3350 4500);
DISPLAY INVISIBLE (-3350 4500);
FORCEADD TAP..6
(-3350 4450);
FORCEPROP 3 LASTPIN (-3300 4450) SIG_NAME M_H_MA<8>
J 0
(-3290 4460);
DISPLAY 0.659574 (-3290 4460);
PAINT MONO (-3290 4460);
DISPLAY INVISIBLE (-3290 4460);
FORCEPROP 1 LASTPIN (-3300 4450) BN 8
J 0
(-3350 4460);
DISPLAY 0.617021 (-3350 4460);
PAINT PINK (-3350 4460);
FORCEPROP 2 LAST CDS_LIB mstr_standard
J 2
(-3350 4450);
DISPLAY 0.787234 (-3350 4450);
PAINT MONO (-3350 4450);
DISPLAY INVISIBLE (-3350 4450);
FORCEPROP 1 LAST BODY_TYPE PLUMBING
J 0
(-3350 4400);
DISPLAY 1.234043 (-3350 4400);
PAINT GREEN (-3350 4400);
DISPLAY INVISIBLE (-3350 4400);
FORCEPROP 1 LAST HDL_TAP TRUE
J 0
(-3025 4325);
DISPLAY 1.234043 (-3025 4325);
PAINT GREEN (-3025 4325);
DISPLAY INVISIBLE (-3025 4325);
FORCEPROP 1 LAST PATH I121
J 0
(-3350 4450);
DISPLAY 0.936170 (-3350 4450);
PAINT GREEN (-3350 4450);
DISPLAY INVISIBLE (-3350 4450);
FORCEADD TAP..6
(-3350 4350);
FORCEPROP 3 LASTPIN (-3300 4350) SIG_NAME M_H_MA<6>
J 0
(-3290 4360);
DISPLAY 0.659574 (-3290 4360);
PAINT MONO (-3290 4360);
DISPLAY INVISIBLE (-3290 4360);
FORCEPROP 1 LASTPIN (-3300 4350) BN 6
J 0
(-3350 4360);
DISPLAY 0.617021 (-3350 4360);
PAINT PINK (-3350 4360);
FORCEPROP 2 LAST CDS_LIB mstr_standard
J 2
(-3350 4350);
DISPLAY 0.787234 (-3350 4350);
PAINT MONO (-3350 4350);
DISPLAY INVISIBLE (-3350 4350);
FORCEPROP 1 LAST BODY_TYPE PLUMBING
J 0
(-3350 4300);
DISPLAY 1.234043 (-3350 4300);
PAINT GREEN (-3350 4300);
DISPLAY INVISIBLE (-3350 4300);
FORCEPROP 1 LAST HDL_TAP TRUE
J 0
(-3025 4225);
DISPLAY 1.234043 (-3025 4225);
PAINT GREEN (-3025 4225);
DISPLAY INVISIBLE (-3025 4225);
FORCEPROP 1 LAST PATH I122
J 0
(-3350 4350);
DISPLAY 0.936170 (-3350 4350);
PAINT GREEN (-3350 4350);
DISPLAY INVISIBLE (-3350 4350);
FORCEADD TAP..6
(-3350 4400);
FORCEPROP 3 LASTPIN (-3300 4400) SIG_NAME M_H_MA<7>
J 0
(-3290 4410);
DISPLAY 0.659574 (-3290 4410);
PAINT MONO (-3290 4410);
DISPLAY INVISIBLE (-3290 4410);
FORCEPROP 1 LASTPIN (-3300 4400) BN 7
J 0
(-3350 4410);
DISPLAY 0.617021 (-3350 4410);
PAINT PINK (-3350 4410);
FORCEPROP 2 LAST CDS_LIB mstr_standard
J 2
(-3350 4400);
DISPLAY 0.787234 (-3350 4400);
PAINT MONO (-3350 4400);
DISPLAY INVISIBLE (-3350 4400);
FORCEPROP 1 LAST BODY_TYPE PLUMBING
J 0
(-3350 4350);
DISPLAY 1.234043 (-3350 4350);
PAINT GREEN (-3350 4350);
DISPLAY INVISIBLE (-3350 4350);
FORCEPROP 1 LAST HDL_TAP TRUE
J 0
(-3025 4275);
DISPLAY 1.234043 (-3025 4275);
PAINT GREEN (-3025 4275);
DISPLAY INVISIBLE (-3025 4275);
FORCEPROP 1 LAST PATH I123
J 0
(-3350 4400);
DISPLAY 0.936170 (-3350 4400);
PAINT GREEN (-3350 4400);
DISPLAY INVISIBLE (-3350 4400);
FORCEADD TAP..6
(-3350 4300);
FORCEPROP 3 LASTPIN (-3300 4300) SIG_NAME M_H_MA<5>
J 0
(-3290 4310);
DISPLAY 0.659574 (-3290 4310);
PAINT MONO (-3290 4310);
DISPLAY INVISIBLE (-3290 4310);
FORCEPROP 1 LASTPIN (-3300 4300) BN 5
J 0
(-3350 4310);
DISPLAY 0.617021 (-3350 4310);
PAINT PINK (-3350 4310);
FORCEPROP 2 LAST CDS_LIB mstr_standard
J 2
(-3350 4300);
DISPLAY 0.787234 (-3350 4300);
PAINT MONO (-3350 4300);
DISPLAY INVISIBLE (-3350 4300);
FORCEPROP 1 LAST BODY_TYPE PLUMBING
J 0
(-3350 4250);
DISPLAY 1.234043 (-3350 4250);
PAINT GREEN (-3350 4250);
DISPLAY INVISIBLE (-3350 4250);
FORCEPROP 1 LAST HDL_TAP TRUE
J 0
(-3025 4175);
DISPLAY 1.234043 (-3025 4175);
PAINT GREEN (-3025 4175);
DISPLAY INVISIBLE (-3025 4175);
FORCEPROP 1 LAST PATH I124
J 0
(-3350 4300);
DISPLAY 0.936170 (-3350 4300);
PAINT GREEN (-3350 4300);
DISPLAY INVISIBLE (-3350 4300);
FORCEADD TAP..6
(-3350 4200);
FORCEPROP 3 LASTPIN (-3300 4200) SIG_NAME M_H_MA<3>
J 0
(-3290 4210);
DISPLAY 0.659574 (-3290 4210);
PAINT MONO (-3290 4210);
DISPLAY INVISIBLE (-3290 4210);
FORCEPROP 1 LASTPIN (-3300 4200) BN 3
J 0
(-3350 4210);
DISPLAY 0.617021 (-3350 4210);
PAINT PINK (-3350 4210);
FORCEPROP 2 LAST CDS_LIB mstr_standard
J 2
(-3350 4200);
DISPLAY 0.787234 (-3350 4200);
PAINT MONO (-3350 4200);
DISPLAY INVISIBLE (-3350 4200);
FORCEPROP 1 LAST BODY_TYPE PLUMBING
J 0
(-3350 4150);
DISPLAY 1.234043 (-3350 4150);
PAINT GREEN (-3350 4150);
DISPLAY INVISIBLE (-3350 4150);
FORCEPROP 1 LAST HDL_TAP TRUE
J 0
(-3025 4075);
DISPLAY 1.234043 (-3025 4075);
PAINT GREEN (-3025 4075);
DISPLAY INVISIBLE (-3025 4075);
FORCEPROP 1 LAST PATH I125
J 0
(-3350 4200);
DISPLAY 0.936170 (-3350 4200);
PAINT GREEN (-3350 4200);
DISPLAY INVISIBLE (-3350 4200);
FORCEADD TAP..6
(-3350 4250);
FORCEPROP 3 LASTPIN (-3300 4250) SIG_NAME M_H_MA<4>
J 0
(-3290 4260);
DISPLAY 0.659574 (-3290 4260);
PAINT MONO (-3290 4260);
DISPLAY INVISIBLE (-3290 4260);
FORCEPROP 1 LASTPIN (-3300 4250) BN 4
J 0
(-3350 4260);
DISPLAY 0.617021 (-3350 4260);
PAINT PINK (-3350 4260);
FORCEPROP 2 LAST CDS_LIB mstr_standard
J 2
(-3350 4250);
DISPLAY 0.787234 (-3350 4250);
PAINT MONO (-3350 4250);
DISPLAY INVISIBLE (-3350 4250);
FORCEPROP 1 LAST BODY_TYPE PLUMBING
J 0
(-3350 4200);
DISPLAY 1.234043 (-3350 4200);
PAINT GREEN (-3350 4200);
DISPLAY INVISIBLE (-3350 4200);
FORCEPROP 1 LAST HDL_TAP TRUE
J 0
(-3025 4125);
DISPLAY 1.234043 (-3025 4125);
PAINT GREEN (-3025 4125);
DISPLAY INVISIBLE (-3025 4125);
FORCEPROP 1 LAST PATH I126
J 0
(-3350 4250);
DISPLAY 0.936170 (-3350 4250);
PAINT GREEN (-3350 4250);
DISPLAY INVISIBLE (-3350 4250);
FORCEADD TAP..6
(-3350 4150);
FORCEPROP 3 LASTPIN (-3300 4150) SIG_NAME M_H_MA<2>
J 0
(-3290 4160);
DISPLAY 0.659574 (-3290 4160);
PAINT MONO (-3290 4160);
DISPLAY INVISIBLE (-3290 4160);
FORCEPROP 1 LASTPIN (-3300 4150) BN 2
J 0
(-3350 4160);
DISPLAY 0.617021 (-3350 4160);
PAINT PINK (-3350 4160);
FORCEPROP 2 LAST CDS_LIB mstr_standard
J 2
(-3350 4150);
DISPLAY 0.787234 (-3350 4150);
PAINT MONO (-3350 4150);
DISPLAY INVISIBLE (-3350 4150);
FORCEPROP 1 LAST BODY_TYPE PLUMBING
J 0
(-3350 4100);
DISPLAY 1.234043 (-3350 4100);
PAINT GREEN (-3350 4100);
DISPLAY INVISIBLE (-3350 4100);
FORCEPROP 1 LAST HDL_TAP TRUE
J 0
(-3025 4025);
DISPLAY 1.234043 (-3025 4025);
PAINT GREEN (-3025 4025);
DISPLAY INVISIBLE (-3025 4025);
FORCEPROP 1 LAST PATH I127
J 0
(-3350 4150);
DISPLAY 0.936170 (-3350 4150);
PAINT GREEN (-3350 4150);
DISPLAY INVISIBLE (-3350 4150);
FORCEADD TAP..6
(-3350 4050);
FORCEPROP 3 LASTPIN (-3300 4050) SIG_NAME M_H_MA<0>
J 0
(-3290 4060);
DISPLAY 0.659574 (-3290 4060);
PAINT MONO (-3290 4060);
DISPLAY INVISIBLE (-3290 4060);
FORCEPROP 1 LASTPIN (-3300 4050) BN 0
J 0
(-3350 4060);
DISPLAY 0.617021 (-3350 4060);
PAINT PINK (-3350 4060);
FORCEPROP 2 LAST CDS_LIB mstr_standard
J 2
(-3350 4050);
DISPLAY 0.787234 (-3350 4050);
PAINT MONO (-3350 4050);
DISPLAY INVISIBLE (-3350 4050);
FORCEPROP 1 LAST BODY_TYPE PLUMBING
J 0
(-3350 4000);
DISPLAY 1.234043 (-3350 4000);
PAINT GREEN (-3350 4000);
DISPLAY INVISIBLE (-3350 4000);
FORCEPROP 1 LAST HDL_TAP TRUE
J 0
(-3025 3925);
DISPLAY 1.234043 (-3025 3925);
PAINT GREEN (-3025 3925);
DISPLAY INVISIBLE (-3025 3925);
FORCEPROP 1 LAST PATH I128
J 0
(-3350 4050);
DISPLAY 0.936170 (-3350 4050);
PAINT GREEN (-3350 4050);
DISPLAY INVISIBLE (-3350 4050);
FORCEADD TAP..6
(-3350 4100);
FORCEPROP 3 LASTPIN (-3300 4100) SIG_NAME M_H_MA<1>
J 0
(-3290 4110);
DISPLAY 0.659574 (-3290 4110);
PAINT MONO (-3290 4110);
DISPLAY INVISIBLE (-3290 4110);
FORCEPROP 1 LASTPIN (-3300 4100) BN 1
J 0
(-3350 4110);
DISPLAY 0.617021 (-3350 4110);
PAINT PINK (-3350 4110);
FORCEPROP 2 LAST CDS_LIB mstr_standard
J 2
(-3350 4100);
DISPLAY 0.787234 (-3350 4100);
PAINT MONO (-3350 4100);
DISPLAY INVISIBLE (-3350 4100);
FORCEPROP 1 LAST BODY_TYPE PLUMBING
J 0
(-3350 4050);
DISPLAY 1.234043 (-3350 4050);
PAINT GREEN (-3350 4050);
DISPLAY INVISIBLE (-3350 4050);
FORCEPROP 1 LAST HDL_TAP TRUE
J 0
(-3025 3975);
DISPLAY 1.234043 (-3025 3975);
PAINT GREEN (-3025 3975);
DISPLAY INVISIBLE (-3025 3975);
FORCEPROP 1 LAST PATH I129
J 0
(-3350 4100);
DISPLAY 0.936170 (-3350 4100);
PAINT GREEN (-3350 4100);
DISPLAY INVISIBLE (-3350 4100);
FORCEADD TAP..6
R 2
(650 4650);
FORCEPROP 3 LASTPIN (600 4650) SIG_NAME M_H_DQS_DP<12>
J 0
(610 4660);
DISPLAY 0.659574 (610 4660);
PAINT MONO (610 4660);
DISPLAY INVISIBLE (610 4660);
FORCEPROP 1 LASTPIN (600 4650) BN 12
J 2
(650 4660);
DISPLAY 0.617021 (650 4660);
PAINT PINK (650 4660);
FORCEPROP 2 LAST CDS_LIB mstr_standard
J 0
(650 4650);
DISPLAY 0.787234 (650 4650);
PAINT MONO (650 4650);
DISPLAY INVISIBLE (650 4650);
FORCEPROP 1 LAST BODY_TYPE PLUMBING
J 2
(650 4600);
DISPLAY 1.234043 (650 4600);
PAINT GREEN (650 4600);
DISPLAY INVISIBLE (650 4600);
FORCEPROP 1 LAST HDL_TAP TRUE
J 2
(325 4525);
DISPLAY 1.234043 (325 4525);
PAINT GREEN (325 4525);
DISPLAY INVISIBLE (325 4525);
FORCEPROP 1 LAST PATH I13
J 2
(650 4650);
DISPLAY 0.936170 (650 4650);
PAINT GREEN (650 4650);
DISPLAY INVISIBLE (650 4650);
FORCEADD OFFPAGE..1
(-4000 4950);
FORCEPROP 2 LAST $XR0 58 
J 0
(-4251 4950);
DISPLAY 0.638298 (-4251 4950);
PAINT MONO (-4251 4950);
FORCEPROP 2 LAST $XR1 80 
J 0
(-4341 4950);
DISPLAY 0.638298 (-4341 4950);
PAINT MONO (-4341 4950);
FORCEPROP 2 LAST CDS_LIB mstr_standard
J 0
(-4000 4950);
DISPLAY 0.787234 (-4000 4950);
PAINT MONO (-4000 4950);
DISPLAY INVISIBLE (-4000 4950);
FORCEPROP 1 LAST OFFPAGE TRUE
J 0
(-3675 4825);
DISPLAY 0.936170 (-3675 4825);
PAINT GREEN (-3675 4825);
DISPLAY INVISIBLE (-3675 4825);
FORCEPROP 1 LAST COMMENT_BODY TRUE
J 0
(-3875 4850);
DISPLAY 0.936170 (-3875 4850);
PAINT GREEN (-3875 4850);
DISPLAY INVISIBLE (-3875 4850);
FORCEPROP 2 LAST PATH I130
J 0
(-3950 5025);
DISPLAY 0.787234 (-3950 5025);
PAINT MONO (-3950 5025);
DISPLAY INVISIBLE (-3950 5025);
FORCEADD TAP..6
(-3350 3950);
FORCEPROP 3 LASTPIN (-3300 3950) SIG_NAME M_H_BA<1>
J 0
(-3290 3960);
DISPLAY 0.659574 (-3290 3960);
PAINT MONO (-3290 3960);
DISPLAY INVISIBLE (-3290 3960);
FORCEPROP 1 LASTPIN (-3300 3950) BN 1
J 0
(-3350 3960);
DISPLAY 0.617021 (-3350 3960);
PAINT PINK (-3350 3960);
FORCEPROP 2 LAST CDS_LIB mstr_standard
J 0
(-3350 3950);
DISPLAY 0.787234 (-3350 3950);
PAINT MONO (-3350 3950);
DISPLAY INVISIBLE (-3350 3950);
FORCEPROP 1 LAST BODY_TYPE PLUMBING
J 0
(-3350 3900);
DISPLAY 1.234043 (-3350 3900);
PAINT GREEN (-3350 3900);
DISPLAY INVISIBLE (-3350 3900);
FORCEPROP 1 LAST HDL_TAP TRUE
J 0
(-3025 3825);
DISPLAY 1.234043 (-3025 3825);
PAINT GREEN (-3025 3825);
DISPLAY INVISIBLE (-3025 3825);
FORCEPROP 1 LAST PATH I131
J 0
(-3350 3950);
DISPLAY 0.936170 (-3350 3950);
PAINT GREEN (-3350 3950);
DISPLAY INVISIBLE (-3350 3950);
FORCEADD TAP..6
(-3350 3900);
FORCEPROP 3 LASTPIN (-3300 3900) SIG_NAME M_H_BA<0>
J 0
(-3290 3910);
DISPLAY 0.659574 (-3290 3910);
PAINT MONO (-3290 3910);
DISPLAY INVISIBLE (-3290 3910);
FORCEPROP 1 LASTPIN (-3300 3900) BN 0
J 0
(-3350 3910);
DISPLAY 0.617021 (-3350 3910);
PAINT PINK (-3350 3910);
FORCEPROP 2 LAST CDS_LIB mstr_standard
J 0
(-3350 3900);
DISPLAY 0.787234 (-3350 3900);
PAINT MONO (-3350 3900);
DISPLAY INVISIBLE (-3350 3900);
FORCEPROP 1 LAST BODY_TYPE PLUMBING
J 0
(-3350 3850);
DISPLAY 1.234043 (-3350 3850);
PAINT GREEN (-3350 3850);
DISPLAY INVISIBLE (-3350 3850);
FORCEPROP 1 LAST HDL_TAP TRUE
J 0
(-3025 3775);
DISPLAY 1.234043 (-3025 3775);
PAINT GREEN (-3025 3775);
DISPLAY INVISIBLE (-3025 3775);
FORCEPROP 1 LAST PATH I132
J 0
(-3350 3900);
DISPLAY 0.936170 (-3350 3900);
PAINT GREEN (-3350 3900);
DISPLAY INVISIBLE (-3350 3900);
FORCEADD TAP..6
(-3350 3800);
FORCEPROP 3 LASTPIN (-3300 3800) SIG_NAME M_H_BG<0>
J 0
(-3290 3810);
DISPLAY 0.659574 (-3290 3810);
PAINT MONO (-3290 3810);
DISPLAY INVISIBLE (-3290 3810);
FORCEPROP 1 LASTPIN (-3300 3800) BN 0
J 0
(-3350 3810);
DISPLAY 0.617021 (-3350 3810);
PAINT PINK (-3350 3810);
FORCEPROP 2 LAST CDS_LIB mstr_standard
J 0
(-3350 3800);
DISPLAY 0.787234 (-3350 3800);
PAINT MONO (-3350 3800);
DISPLAY INVISIBLE (-3350 3800);
FORCEPROP 1 LAST BODY_TYPE PLUMBING
J 0
(-3350 3750);
DISPLAY 1.234043 (-3350 3750);
PAINT GREEN (-3350 3750);
DISPLAY INVISIBLE (-3350 3750);
FORCEPROP 1 LAST HDL_TAP TRUE
J 0
(-3025 3675);
DISPLAY 1.234043 (-3025 3675);
PAINT GREEN (-3025 3675);
DISPLAY INVISIBLE (-3025 3675);
FORCEPROP 1 LAST PATH I133
J 0
(-3350 3800);
DISPLAY 0.936170 (-3350 3800);
PAINT GREEN (-3350 3800);
DISPLAY INVISIBLE (-3350 3800);
FORCEADD TAP..6
(-3350 3850);
FORCEPROP 3 LASTPIN (-3300 3850) SIG_NAME M_H_BG<1>
J 0
(-3290 3860);
DISPLAY 0.659574 (-3290 3860);
PAINT MONO (-3290 3860);
DISPLAY INVISIBLE (-3290 3860);
FORCEPROP 1 LASTPIN (-3300 3850) BN 1
J 0
(-3350 3860);
DISPLAY 0.617021 (-3350 3860);
PAINT PINK (-3350 3860);
FORCEPROP 2 LAST CDS_LIB mstr_standard
J 0
(-3350 3850);
DISPLAY 0.787234 (-3350 3850);
PAINT MONO (-3350 3850);
DISPLAY INVISIBLE (-3350 3850);
FORCEPROP 1 LAST BODY_TYPE PLUMBING
J 0
(-3350 3800);
DISPLAY 1.234043 (-3350 3800);
PAINT GREEN (-3350 3800);
DISPLAY INVISIBLE (-3350 3800);
FORCEPROP 1 LAST HDL_TAP TRUE
J 0
(-3025 3725);
DISPLAY 1.234043 (-3025 3725);
PAINT GREEN (-3025 3725);
DISPLAY INVISIBLE (-3025 3725);
FORCEPROP 1 LAST PATH I134
J 0
(-3350 3850);
DISPLAY 0.936170 (-3350 3850);
PAINT GREEN (-3350 3850);
DISPLAY INVISIBLE (-3350 3850);
FORCEADD OFFPAGE..1
(-4000 3500);
FORCEPROP 2 LAST $XR0 58 
J 0
(-4251 3500);
DISPLAY 0.638298 (-4251 3500);
PAINT MONO (-4251 3500);
FORCEPROP 2 LAST $XR1 80 
J 0
(-4341 3500);
DISPLAY 0.638298 (-4341 3500);
PAINT MONO (-4341 3500);
FORCEPROP 2 LAST CDS_LIB mstr_standard
J 0
(-4000 3500);
DISPLAY 0.787234 (-4000 3500);
PAINT MONO (-4000 3500);
DISPLAY INVISIBLE (-4000 3500);
FORCEPROP 1 LAST OFFPAGE TRUE
J 0
(-3675 3375);
DISPLAY 0.936170 (-3675 3375);
PAINT GREEN (-3675 3375);
DISPLAY INVISIBLE (-3675 3375);
FORCEPROP 1 LAST COMMENT_BODY TRUE
J 0
(-3875 3400);
DISPLAY 0.936170 (-3875 3400);
PAINT GREEN (-3875 3400);
DISPLAY INVISIBLE (-3875 3400);
FORCEPROP 2 LAST PATH I135
J 0
(-3950 3575);
DISPLAY 0.787234 (-3950 3575);
PAINT MONO (-3950 3575);
DISPLAY INVISIBLE (-3950 3575);
FORCEADD OFFPAGE..1
(-4000 4000);
FORCEPROP 2 LAST $XR0 58 
J 0
(-4251 4000);
DISPLAY 0.638298 (-4251 4000);
PAINT MONO (-4251 4000);
FORCEPROP 2 LAST $XR1 80 
J 0
(-4341 4000);
DISPLAY 0.638298 (-4341 4000);
PAINT MONO (-4341 4000);
FORCEPROP 2 LAST CDS_LIB mstr_standard
J 0
(-4000 4000);
DISPLAY 0.787234 (-4000 4000);
PAINT MONO (-4000 4000);
DISPLAY INVISIBLE (-4000 4000);
FORCEPROP 1 LAST OFFPAGE TRUE
J 0
(-3675 3875);
DISPLAY 0.936170 (-3675 3875);
PAINT GREEN (-3675 3875);
DISPLAY INVISIBLE (-3675 3875);
FORCEPROP 1 LAST COMMENT_BODY TRUE
J 0
(-3875 3900);
DISPLAY 0.936170 (-3875 3900);
PAINT GREEN (-3875 3900);
DISPLAY INVISIBLE (-3875 3900);
FORCEPROP 2 LAST PATH I136
J 0
(-3950 4075);
DISPLAY 0.787234 (-3950 4075);
PAINT MONO (-3950 4075);
DISPLAY INVISIBLE (-3950 4075);
FORCEADD OFFPAGE..1
(-4000 3900);
FORCEPROP 2 LAST $XR0 58 
J 0
(-4251 3900);
DISPLAY 0.638298 (-4251 3900);
PAINT MONO (-4251 3900);
FORCEPROP 2 LAST $XR1 80 
J 0
(-4341 3900);
DISPLAY 0.638298 (-4341 3900);
PAINT MONO (-4341 3900);
FORCEPROP 2 LAST CDS_LIB mstr_standard
J 0
(-4000 3900);
DISPLAY 0.787234 (-4000 3900);
PAINT MONO (-4000 3900);
DISPLAY INVISIBLE (-4000 3900);
FORCEPROP 1 LAST OFFPAGE TRUE
J 0
(-3675 3775);
DISPLAY 0.936170 (-3675 3775);
PAINT GREEN (-3675 3775);
DISPLAY INVISIBLE (-3675 3775);
FORCEPROP 1 LAST COMMENT_BODY TRUE
J 0
(-3875 3800);
DISPLAY 0.936170 (-3875 3800);
PAINT GREEN (-3875 3800);
DISPLAY INVISIBLE (-3875 3800);
FORCEPROP 2 LAST PATH I137
J 0
(-3950 3975);
DISPLAY 0.787234 (-3950 3975);
PAINT MONO (-3950 3975);
DISPLAY INVISIBLE (-3950 3975);
FORCEADD TAP..6
(-3350 2800);
FORCEPROP 3 LASTPIN (-3300 2800) SIG_NAME M_H_ECC<7>
J 0
(-3290 2810);
DISPLAY 0.659574 (-3290 2810);
PAINT MONO (-3290 2810);
DISPLAY INVISIBLE (-3290 2810);
FORCEPROP 1 LASTPIN (-3300 2800) BN 7
J 0
(-3350 2810);
DISPLAY 0.617021 (-3350 2810);
PAINT PINK (-3350 2810);
FORCEPROP 2 LAST CDS_LIB mstr_standard
J 0
(-3350 2800);
DISPLAY 0.787234 (-3350 2800);
PAINT MONO (-3350 2800);
DISPLAY INVISIBLE (-3350 2800);
FORCEPROP 1 LAST BODY_TYPE PLUMBING
J 0
(-3350 2750);
DISPLAY 1.234043 (-3350 2750);
PAINT GREEN (-3350 2750);
DISPLAY INVISIBLE (-3350 2750);
FORCEPROP 1 LAST HDL_TAP TRUE
J 0
(-3025 2675);
DISPLAY 1.234043 (-3025 2675);
PAINT GREEN (-3025 2675);
DISPLAY INVISIBLE (-3025 2675);
FORCEPROP 1 LAST PATH I138
J 0
(-3350 2800);
DISPLAY 0.936170 (-3350 2800);
PAINT GREEN (-3350 2800);
DISPLAY INVISIBLE (-3350 2800);
FORCEADD TAP..6
(-3350 2850);
FORCEPROP 3 LASTPIN (-3300 2850) SIG_NAME M_H_ECC<6>
J 0
(-3290 2860);
DISPLAY 0.659574 (-3290 2860);
PAINT MONO (-3290 2860);
DISPLAY INVISIBLE (-3290 2860);
FORCEPROP 1 LASTPIN (-3300 2850) BN 6
J 0
(-3350 2860);
DISPLAY 0.617021 (-3350 2860);
PAINT PINK (-3350 2860);
FORCEPROP 2 LAST CDS_LIB mstr_standard
J 0
(-3350 2850);
DISPLAY 0.787234 (-3350 2850);
PAINT MONO (-3350 2850);
DISPLAY INVISIBLE (-3350 2850);
FORCEPROP 1 LAST BODY_TYPE PLUMBING
J 0
(-3350 2800);
DISPLAY 1.234043 (-3350 2800);
PAINT GREEN (-3350 2800);
DISPLAY INVISIBLE (-3350 2800);
FORCEPROP 1 LAST HDL_TAP TRUE
J 0
(-3025 2725);
DISPLAY 1.234043 (-3025 2725);
PAINT GREEN (-3025 2725);
DISPLAY INVISIBLE (-3025 2725);
FORCEPROP 1 LAST PATH I139
J 0
(-3350 2850);
DISPLAY 0.936170 (-3350 2850);
PAINT GREEN (-3350 2850);
DISPLAY INVISIBLE (-3350 2850);
FORCEADD PVDDQ_GHJ..1
(-1525 2525);
FORCEPROP 3 LASTPIN (-1525 2475) SIG_NAME PVDDQ_GHJ\g
J 0
(-1515 2485);
DISPLAY 0.659574 (-1515 2485);
PAINT MONO (-1515 2485);
DISPLAY INVISIBLE (-1515 2485);
FORCEPROP 1 LAST VOLTAGE 1.2V
J 0
(-1570 2482);
DISPLAY 0.340426 (-1570 2482);
PAINT SKYBLUE (-1570 2482);
DISPLAY INVISIBLE (-1570 2482);
FORCEPROP 2 LAST BOM_COST MEM
J 0
(-1525 2530);
PAINT ORANGE (-1525 2530);
DISPLAY INVISIBLE (-1525 2530);
FORCEPROP 2 LAST CDS_LIB mstr_symbols
J 0
(-1525 2525);
PAINT ORANGE (-1525 2525);
DISPLAY INVISIBLE (-1525 2525);
FORCEPROP 1 LAST BODY_TYPE PLUMBING
J 0
(-1570 2482);
DISPLAY 0.340426 (-1570 2482);
PAINT GREEN (-1570 2482);
DISPLAY INVISIBLE (-1570 2482);
FORCEPROP 1 LAST PATH I14
J 0
(-1475 2550);
DISPLAY 0.872340 (-1475 2550);
PAINT AQUA (-1475 2550);
DISPLAY INVISIBLE (-1475 2550);
FORCEPROP 2 LAST ROOM DDR4_CH_H
J 0
(-1525 2625);
DISPLAY 0.787234 (-1525 2625);
PAINT ORANGE (-1525 2625);
DISPLAY INVISIBLE (-1525 2625);
FORCEPROP 1 LAST HDL_POWER PVDDQ_GHJ
J 1
(-1525 2575);
DISPLAY 0.872340 (-1525 2575);
PAINT GREEN (-1525 2575);
DISPLAY INVISIBLE (-1525 2575);
FORCEADD TAP..6
(-3350 2750);
FORCEPROP 3 LASTPIN (-3300 2750) SIG_NAME M_H_ECC<4>
J 0
(-3290 2760);
DISPLAY 0.659574 (-3290 2760);
PAINT MONO (-3290 2760);
DISPLAY INVISIBLE (-3290 2760);
FORCEPROP 1 LASTPIN (-3300 2750) BN 4
J 0
(-3350 2760);
DISPLAY 0.617021 (-3350 2760);
PAINT PINK (-3350 2760);
FORCEPROP 2 LAST CDS_LIB mstr_standard
J 0
(-3350 2750);
DISPLAY 0.787234 (-3350 2750);
PAINT MONO (-3350 2750);
DISPLAY INVISIBLE (-3350 2750);
FORCEPROP 1 LAST BODY_TYPE PLUMBING
J 0
(-3350 2700);
DISPLAY 1.234043 (-3350 2700);
PAINT GREEN (-3350 2700);
DISPLAY INVISIBLE (-3350 2700);
FORCEPROP 1 LAST HDL_TAP TRUE
J 0
(-3025 2625);
DISPLAY 1.234043 (-3025 2625);
PAINT GREEN (-3025 2625);
DISPLAY INVISIBLE (-3025 2625);
FORCEPROP 1 LAST PATH I140
J 0
(-3350 2750);
DISPLAY 0.936170 (-3350 2750);
PAINT GREEN (-3350 2750);
DISPLAY INVISIBLE (-3350 2750);
FORCEADD TAP..6
(-3350 2700);
FORCEPROP 3 LASTPIN (-3300 2700) SIG_NAME M_H_ECC<5>
J 0
(-3290 2710);
DISPLAY 0.659574 (-3290 2710);
PAINT MONO (-3290 2710);
DISPLAY INVISIBLE (-3290 2710);
FORCEPROP 1 LASTPIN (-3300 2700) BN 5
J 0
(-3350 2710);
DISPLAY 0.617021 (-3350 2710);
PAINT PINK (-3350 2710);
FORCEPROP 2 LAST CDS_LIB mstr_standard
J 0
(-3350 2700);
DISPLAY 0.787234 (-3350 2700);
PAINT MONO (-3350 2700);
DISPLAY INVISIBLE (-3350 2700);
FORCEPROP 1 LAST BODY_TYPE PLUMBING
J 0
(-3350 2650);
DISPLAY 1.234043 (-3350 2650);
PAINT GREEN (-3350 2650);
DISPLAY INVISIBLE (-3350 2650);
FORCEPROP 1 LAST HDL_TAP TRUE
J 0
(-3025 2575);
DISPLAY 1.234043 (-3025 2575);
PAINT GREEN (-3025 2575);
DISPLAY INVISIBLE (-3025 2575);
FORCEPROP 1 LAST PATH I141
J 0
(-3350 2700);
DISPLAY 0.936170 (-3350 2700);
PAINT GREEN (-3350 2700);
DISPLAY INVISIBLE (-3350 2700);
FORCEADD TAP..6
(-3350 2650);
FORCEPROP 3 LASTPIN (-3300 2650) SIG_NAME M_H_ECC<2>
J 0
(-3290 2660);
DISPLAY 0.659574 (-3290 2660);
PAINT MONO (-3290 2660);
DISPLAY INVISIBLE (-3290 2660);
FORCEPROP 1 LASTPIN (-3300 2650) BN 2
J 0
(-3350 2660);
DISPLAY 0.617021 (-3350 2660);
PAINT PINK (-3350 2660);
FORCEPROP 2 LAST CDS_LIB mstr_standard
J 0
(-3350 2650);
DISPLAY 0.787234 (-3350 2650);
PAINT MONO (-3350 2650);
DISPLAY INVISIBLE (-3350 2650);
FORCEPROP 1 LAST BODY_TYPE PLUMBING
J 0
(-3350 2600);
DISPLAY 1.234043 (-3350 2600);
PAINT GREEN (-3350 2600);
DISPLAY INVISIBLE (-3350 2600);
FORCEPROP 1 LAST HDL_TAP TRUE
J 0
(-3025 2525);
DISPLAY 1.234043 (-3025 2525);
PAINT GREEN (-3025 2525);
DISPLAY INVISIBLE (-3025 2525);
FORCEPROP 1 LAST PATH I142
J 0
(-3350 2650);
DISPLAY 0.936170 (-3350 2650);
PAINT GREEN (-3350 2650);
DISPLAY INVISIBLE (-3350 2650);
FORCEADD TAP..6
(-3350 2550);
FORCEPROP 3 LASTPIN (-3300 2550) SIG_NAME M_H_ECC<0>
J 0
(-3290 2560);
DISPLAY 0.659574 (-3290 2560);
PAINT MONO (-3290 2560);
DISPLAY INVISIBLE (-3290 2560);
FORCEPROP 1 LASTPIN (-3300 2550) BN 0
J 0
(-3350 2560);
DISPLAY 0.617021 (-3350 2560);
PAINT PINK (-3350 2560);
FORCEPROP 2 LAST CDS_LIB mstr_standard
J 0
(-3350 2550);
DISPLAY 0.787234 (-3350 2550);
PAINT MONO (-3350 2550);
DISPLAY INVISIBLE (-3350 2550);
FORCEPROP 1 LAST BODY_TYPE PLUMBING
J 0
(-3350 2500);
DISPLAY 1.234043 (-3350 2500);
PAINT GREEN (-3350 2500);
DISPLAY INVISIBLE (-3350 2500);
FORCEPROP 1 LAST HDL_TAP TRUE
J 0
(-3025 2425);
DISPLAY 1.234043 (-3025 2425);
PAINT GREEN (-3025 2425);
DISPLAY INVISIBLE (-3025 2425);
FORCEPROP 1 LAST PATH I143
J 0
(-3350 2550);
DISPLAY 0.936170 (-3350 2550);
PAINT GREEN (-3350 2550);
DISPLAY INVISIBLE (-3350 2550);
FORCEADD TAP..6
(-3350 2600);
FORCEPROP 3 LASTPIN (-3300 2600) SIG_NAME M_H_ECC<3>
J 0
(-3290 2610);
DISPLAY 0.659574 (-3290 2610);
PAINT MONO (-3290 2610);
DISPLAY INVISIBLE (-3290 2610);
FORCEPROP 1 LASTPIN (-3300 2600) BN 3
J 0
(-3350 2610);
DISPLAY 0.617021 (-3350 2610);
PAINT PINK (-3350 2610);
FORCEPROP 2 LAST CDS_LIB mstr_standard
J 0
(-3350 2600);
DISPLAY 0.787234 (-3350 2600);
PAINT MONO (-3350 2600);
DISPLAY INVISIBLE (-3350 2600);
FORCEPROP 1 LAST BODY_TYPE PLUMBING
J 0
(-3350 2550);
DISPLAY 1.234043 (-3350 2550);
PAINT GREEN (-3350 2550);
DISPLAY INVISIBLE (-3350 2550);
FORCEPROP 1 LAST HDL_TAP TRUE
J 0
(-3025 2475);
DISPLAY 1.234043 (-3025 2475);
PAINT GREEN (-3025 2475);
DISPLAY INVISIBLE (-3025 2475);
FORCEPROP 1 LAST PATH I144
J 0
(-3350 2600);
DISPLAY 0.936170 (-3350 2600);
PAINT GREEN (-3350 2600);
DISPLAY INVISIBLE (-3350 2600);
FORCEADD TAP..6
(-3350 2500);
FORCEPROP 3 LASTPIN (-3300 2500) SIG_NAME M_H_ECC<1>
J 0
(-3290 2510);
DISPLAY 0.659574 (-3290 2510);
PAINT MONO (-3290 2510);
DISPLAY INVISIBLE (-3290 2510);
FORCEPROP 1 LASTPIN (-3300 2500) BN 1
J 0
(-3350 2510);
DISPLAY 0.617021 (-3350 2510);
PAINT PINK (-3350 2510);
FORCEPROP 2 LAST CDS_LIB mstr_standard
J 0
(-3350 2500);
DISPLAY 0.787234 (-3350 2500);
PAINT MONO (-3350 2500);
DISPLAY INVISIBLE (-3350 2500);
FORCEPROP 1 LAST BODY_TYPE PLUMBING
J 0
(-3350 2450);
DISPLAY 1.234043 (-3350 2450);
PAINT GREEN (-3350 2450);
DISPLAY INVISIBLE (-3350 2450);
FORCEPROP 1 LAST HDL_TAP TRUE
J 0
(-3025 2375);
DISPLAY 1.234043 (-3025 2375);
PAINT GREEN (-3025 2375);
DISPLAY INVISIBLE (-3025 2375);
FORCEPROP 1 LAST PATH I145
J 0
(-3350 2500);
DISPLAY 0.936170 (-3350 2500);
PAINT GREEN (-3350 2500);
DISPLAY INVISIBLE (-3350 2500);
FORCEADD OFFPAGE..1
(-4000 2850);
FORCEPROP 2 LAST $XR0 58 
J 0
(-4251 2850);
DISPLAY 0.638298 (-4251 2850);
PAINT MONO (-4251 2850);
FORCEPROP 2 LAST $XR1 80 
J 0
(-4341 2850);
DISPLAY 0.638298 (-4341 2850);
PAINT MONO (-4341 2850);
FORCEPROP 2 LAST CDS_LIB mstr_standard
J 0
(-4000 2850);
DISPLAY 0.787234 (-4000 2850);
PAINT MONO (-4000 2850);
DISPLAY INVISIBLE (-4000 2850);
FORCEPROP 1 LAST OFFPAGE TRUE
J 0
(-3675 2725);
DISPLAY 0.936170 (-3675 2725);
PAINT GREEN (-3675 2725);
DISPLAY INVISIBLE (-3675 2725);
FORCEPROP 1 LAST COMMENT_BODY TRUE
J 0
(-3875 2750);
DISPLAY 0.936170 (-3875 2750);
PAINT GREEN (-3875 2750);
DISPLAY INVISIBLE (-3875 2750);
FORCEPROP 2 LAST PATH I146
J 0
(-3950 2925);
DISPLAY 0.787234 (-3950 2925);
PAINT MONO (-3950 2925);
DISPLAY INVISIBLE (-3950 2925);
FORCEADD OFFPAGE..1
(-4000 2200);
FORCEPROP 2 LAST $XR0 58 
J 0
(-4251 2200);
DISPLAY 0.638298 (-4251 2200);
PAINT MONO (-4251 2200);
FORCEPROP 2 LAST $XR1 80 
J 0
(-4341 2200);
DISPLAY 0.638298 (-4341 2200);
PAINT MONO (-4341 2200);
FORCEPROP 2 LAST CDS_LIB mstr_standard
J 0
(-4000 2200);
DISPLAY 0.787234 (-4000 2200);
PAINT MONO (-4000 2200);
DISPLAY INVISIBLE (-4000 2200);
FORCEPROP 1 LAST OFFPAGE TRUE
J 0
(-3675 2075);
DISPLAY 0.936170 (-3675 2075);
PAINT GREEN (-3675 2075);
DISPLAY INVISIBLE (-3675 2075);
FORCEPROP 1 LAST COMMENT_BODY TRUE
J 0
(-3875 2100);
DISPLAY 0.936170 (-3875 2100);
PAINT GREEN (-3875 2100);
DISPLAY INVISIBLE (-3875 2100);
FORCEPROP 2 LAST PATH I147
J 0
(-3950 2275);
DISPLAY 0.787234 (-3950 2275);
PAINT MONO (-3950 2275);
DISPLAY INVISIBLE (-3950 2275);
FORCEADD OFFPAGE..5
(-4025 2250);
FORCEPROP 2 LAST $XR0 80 
J 0
(-4249 2250);
DISPLAY 0.638298 (-4249 2250);
PAINT MONO (-4249 2250);
FORCEPROP 2 LAST $XR1 58 
J 0
(-4339 2250);
DISPLAY 0.638298 (-4339 2250);
PAINT MONO (-4339 2250);
FORCEPROP 2 LAST CDS_LIB mstr_standard
J 0
(-4025 2250);
DISPLAY 0.787234 (-4025 2250);
PAINT MONO (-4025 2250);
DISPLAY INVISIBLE (-4025 2250);
FORCEPROP 1 LAST OFFPAGE TRUE
J 0
(-3700 2125);
DISPLAY 1.404255 (-3700 2125);
PAINT GREEN (-3700 2125);
DISPLAY INVISIBLE (-3700 2125);
FORCEPROP 1 LAST COMMENT_BODY TRUE
J 0
(-3925 2175);
DISPLAY 1.404255 (-3925 2175);
PAINT GREEN (-3925 2175);
DISPLAY INVISIBLE (-3925 2175);
FORCEPROP 2 LAST PATH I148
J 0
(-3975 2325);
DISPLAY 0.787234 (-3975 2325);
PAINT MONO (-3975 2325);
DISPLAY INVISIBLE (-3975 2325);
FORCEADD OFFPAGE..1
(-4000 2800);
FORCEPROP 2 LAST $XR0 55 
J 0
(-4251 2800);
DISPLAY 0.638298 (-4251 2800);
PAINT MONO (-4251 2800);
FORCEPROP 2 LAST $XR1 77 
J 0
(-4341 2800);
DISPLAY 0.638298 (-4341 2800);
PAINT MONO (-4341 2800);
FORCEPROP 2 LAST $XR2 78 
J 0
(-4431 2800);
DISPLAY 0.638298 (-4431 2800);
PAINT MONO (-4431 2800);
FORCEPROP 2 LAST $XR3 80 
J 0
(-4521 2800);
DISPLAY 0.638298 (-4521 2800);
PAINT MONO (-4521 2800);
FORCEPROP 2 LAST $XR4 81 
J 0
(-4611 2800);
DISPLAY 0.638298 (-4611 2800);
PAINT MONO (-4611 2800);
FORCEPROP 2 LAST $XR5 82 
J 0
(-4701 2800);
DISPLAY 0.638298 (-4701 2800);
PAINT MONO (-4701 2800);
FORCEPROP 2 LAST CDS_LIB mstr_standard
J 0
(-4000 2800);
DISPLAY 0.787234 (-4000 2800);
PAINT MONO (-4000 2800);
DISPLAY INVISIBLE (-4000 2800);
FORCEPROP 1 LAST OFFPAGE TRUE
J 0
(-3675 2675);
DISPLAY 0.936170 (-3675 2675);
PAINT GREEN (-3675 2675);
DISPLAY INVISIBLE (-3675 2675);
FORCEPROP 1 LAST COMMENT_BODY TRUE
J 0
(-3875 2700);
DISPLAY 0.936170 (-3875 2700);
PAINT GREEN (-3875 2700);
DISPLAY INVISIBLE (-3875 2700);
FORCEPROP 2 LAST PATH I149
J 0
(-3950 2875);
DISPLAY 0.787234 (-3950 2875);
PAINT MONO (-3950 2875);
DISPLAY INVISIBLE (-3950 2875);
FORCEADD OFFPAGE..6
(-4000 2900);
FORCEPROP 2 LAST $XR0 58 
J 0
(-4249 2900);
DISPLAY 0.638298 (-4249 2900);
PAINT MONO (-4249 2900);
FORCEPROP 2 LAST $XR1 80 
J 0
(-4339 2900);
DISPLAY 0.638298 (-4339 2900);
PAINT MONO (-4339 2900);
FORCEPROP 2 LAST CDS_LIB mstr_standard
J 0
(-4000 2900);
DISPLAY 0.787234 (-4000 2900);
PAINT MONO (-4000 2900);
DISPLAY INVISIBLE (-4000 2900);
FORCEPROP 1 LAST OFFPAGE TRUE
J 0
(-3675 2775);
DISPLAY 0.936170 (-3675 2775);
PAINT GREEN (-3675 2775);
DISPLAY INVISIBLE (-3675 2775);
FORCEPROP 1 LAST COMMENT_BODY TRUE
J 0
(-3900 2825);
DISPLAY 0.936170 (-3900 2825);
PAINT GREEN (-3900 2825);
DISPLAY INVISIBLE (-3900 2825);
FORCEPROP 2 LAST PATH I150
J 0
(-3950 2975);
DISPLAY 0.787234 (-3950 2975);
PAINT MONO (-3950 2975);
DISPLAY INVISIBLE (-3950 2975);
FORCEADD TAP..6
(-3350 3700);
FORCEPROP 3 LASTPIN (-3300 3700) SIG_NAME M_H_CLK_DP<1>
J 0
(-3290 3710);
DISPLAY 0.659574 (-3290 3710);
PAINT MONO (-3290 3710);
DISPLAY INVISIBLE (-3290 3710);
FORCEPROP 1 LASTPIN (-3300 3700) BN 1
J 0
(-3350 3710);
DISPLAY 0.617021 (-3350 3710);
PAINT PINK (-3350 3710);
FORCEPROP 2 LAST CDS_LIB mstr_standard
J 0
(-3350 3700);
DISPLAY 0.787234 (-3350 3700);
PAINT MONO (-3350 3700);
DISPLAY INVISIBLE (-3350 3700);
FORCEPROP 1 LAST BODY_TYPE PLUMBING
J 0
(-3350 3650);
DISPLAY 1.234043 (-3350 3650);
PAINT GREEN (-3350 3650);
DISPLAY INVISIBLE (-3350 3650);
FORCEPROP 1 LAST HDL_TAP TRUE
J 0
(-3025 3575);
DISPLAY 1.234043 (-3025 3575);
PAINT GREEN (-3025 3575);
DISPLAY INVISIBLE (-3025 3575);
FORCEPROP 1 LAST PATH I152
J 0
(-3350 3700);
DISPLAY 0.936170 (-3350 3700);
PAINT GREEN (-3350 3700);
DISPLAY INVISIBLE (-3350 3700);
FORCEADD TAP..6
(-3350 3600);
FORCEPROP 3 LASTPIN (-3300 3600) SIG_NAME M_H_CLK_DP<0>
J 0
(-3290 3610);
DISPLAY 0.659574 (-3290 3610);
PAINT MONO (-3290 3610);
DISPLAY INVISIBLE (-3290 3610);
FORCEPROP 1 LASTPIN (-3300 3600) BN 0
J 0
(-3350 3610);
DISPLAY 0.617021 (-3350 3610);
PAINT PINK (-3350 3610);
FORCEPROP 2 LAST CDS_LIB mstr_standard
J 0
(-3350 3600);
DISPLAY 0.787234 (-3350 3600);
PAINT MONO (-3350 3600);
DISPLAY INVISIBLE (-3350 3600);
FORCEPROP 1 LAST BODY_TYPE PLUMBING
J 0
(-3350 3550);
DISPLAY 1.234043 (-3350 3550);
PAINT GREEN (-3350 3550);
DISPLAY INVISIBLE (-3350 3550);
FORCEPROP 1 LAST HDL_TAP TRUE
J 0
(-3025 3475);
DISPLAY 1.234043 (-3025 3475);
PAINT GREEN (-3025 3475);
DISPLAY INVISIBLE (-3025 3475);
FORCEPROP 1 LAST PATH I153
J 0
(-3350 3600);
DISPLAY 0.936170 (-3350 3600);
PAINT GREEN (-3350 3600);
DISPLAY INVISIBLE (-3350 3600);
FORCEADD TAP..6
(-3550 3650);
FORCEPROP 3 LASTPIN (-3500 3650) SIG_NAME M_H_CLK_DN<1>
J 0
(-3490 3660);
DISPLAY 0.659574 (-3490 3660);
PAINT MONO (-3490 3660);
DISPLAY INVISIBLE (-3490 3660);
FORCEPROP 1 LASTPIN (-3500 3650) BN 1
J 0
(-3550 3660);
DISPLAY 0.617021 (-3550 3660);
PAINT PINK (-3550 3660);
FORCEPROP 2 LAST CDS_LIB mstr_standard
J 0
(-3550 3650);
DISPLAY 0.787234 (-3550 3650);
PAINT MONO (-3550 3650);
DISPLAY INVISIBLE (-3550 3650);
FORCEPROP 1 LAST BODY_TYPE PLUMBING
J 0
(-3550 3600);
DISPLAY 1.234043 (-3550 3600);
PAINT GREEN (-3550 3600);
DISPLAY INVISIBLE (-3550 3600);
FORCEPROP 1 LAST HDL_TAP TRUE
J 0
(-3225 3525);
DISPLAY 1.234043 (-3225 3525);
PAINT GREEN (-3225 3525);
DISPLAY INVISIBLE (-3225 3525);
FORCEPROP 1 LAST PATH I154
J 0
(-3550 3650);
DISPLAY 0.936170 (-3550 3650);
PAINT GREEN (-3550 3650);
DISPLAY INVISIBLE (-3550 3650);
FORCEADD TAP..6
(-3550 3550);
FORCEPROP 3 LASTPIN (-3500 3550) SIG_NAME M_H_CLK_DN<0>
J 0
(-3490 3560);
DISPLAY 0.659574 (-3490 3560);
PAINT MONO (-3490 3560);
DISPLAY INVISIBLE (-3490 3560);
FORCEPROP 1 LASTPIN (-3500 3550) BN 0
J 0
(-3550 3560);
DISPLAY 0.617021 (-3550 3560);
PAINT PINK (-3550 3560);
FORCEPROP 2 LAST CDS_LIB mstr_standard
J 0
(-3550 3550);
DISPLAY 0.787234 (-3550 3550);
PAINT MONO (-3550 3550);
DISPLAY INVISIBLE (-3550 3550);
FORCEPROP 1 LAST BODY_TYPE PLUMBING
J 0
(-3550 3500);
DISPLAY 1.234043 (-3550 3500);
PAINT GREEN (-3550 3500);
DISPLAY INVISIBLE (-3550 3500);
FORCEPROP 1 LAST HDL_TAP TRUE
J 0
(-3225 3425);
DISPLAY 1.234043 (-3225 3425);
PAINT GREEN (-3225 3425);
DISPLAY INVISIBLE (-3225 3425);
FORCEPROP 1 LAST PATH I155
J 0
(-3550 3550);
DISPLAY 0.936170 (-3550 3550);
PAINT GREEN (-3550 3550);
DISPLAY INVISIBLE (-3550 3550);
FORCEADD OFFPAGE..1
(-4000 3700);
FORCEPROP 2 LAST $XR0 58 
J 0
(-4251 3700);
DISPLAY 0.638298 (-4251 3700);
PAINT MONO (-4251 3700);
FORCEPROP 2 LAST $XR1 80 
J 0
(-4341 3700);
DISPLAY 0.638298 (-4341 3700);
PAINT MONO (-4341 3700);
FORCEPROP 2 LAST CDS_LIB mstr_standard
J 0
(-4000 3700);
DISPLAY 0.787234 (-4000 3700);
PAINT MONO (-4000 3700);
DISPLAY INVISIBLE (-4000 3700);
FORCEPROP 1 LAST OFFPAGE TRUE
J 0
(-3675 3575);
DISPLAY 0.936170 (-3675 3575);
PAINT GREEN (-3675 3575);
DISPLAY INVISIBLE (-3675 3575);
FORCEPROP 1 LAST COMMENT_BODY TRUE
J 0
(-3875 3600);
DISPLAY 0.936170 (-3875 3600);
PAINT GREEN (-3875 3600);
DISPLAY INVISIBLE (-3875 3600);
FORCEPROP 2 LAST PATH I156
J 0
(-3950 3775);
DISPLAY 0.787234 (-3950 3775);
PAINT MONO (-3950 3775);
DISPLAY INVISIBLE (-3950 3775);
FORCEADD OFFPAGE..1
(-4000 3750);
FORCEPROP 2 LAST $XR0 58 
J 0
(-4251 3750);
DISPLAY 0.638298 (-4251 3750);
PAINT MONO (-4251 3750);
FORCEPROP 2 LAST $XR1 80 
J 0
(-4341 3750);
DISPLAY 0.638298 (-4341 3750);
PAINT MONO (-4341 3750);
FORCEPROP 2 LAST CDS_LIB mstr_standard
J 0
(-4000 3750);
DISPLAY 0.787234 (-4000 3750);
PAINT MONO (-4000 3750);
DISPLAY INVISIBLE (-4000 3750);
FORCEPROP 1 LAST OFFPAGE TRUE
J 0
(-3675 3625);
DISPLAY 0.936170 (-3675 3625);
PAINT GREEN (-3675 3625);
DISPLAY INVISIBLE (-3675 3625);
FORCEPROP 1 LAST COMMENT_BODY TRUE
J 0
(-3875 3650);
DISPLAY 0.936170 (-3875 3650);
PAINT GREEN (-3875 3650);
DISPLAY INVISIBLE (-3875 3650);
FORCEPROP 2 LAST PATH I157
J 0
(-3950 3825);
DISPLAY 0.787234 (-3950 3825);
PAINT MONO (-3950 3825);
DISPLAY INVISIBLE (-3950 3825);
FORCEADD TAP..6
(-3350 3400);
FORCEPROP 3 LASTPIN (-3300 3400) SIG_NAME M_H_CS_N<3>
J 0
(-3290 3410);
DISPLAY 0.659574 (-3290 3410);
PAINT MONO (-3290 3410);
DISPLAY INVISIBLE (-3290 3410);
FORCEPROP 1 LASTPIN (-3300 3400) BN 3
J 0
(-3350 3410);
DISPLAY 0.617021 (-3350 3410);
PAINT PINK (-3350 3410);
FORCEPROP 2 LAST CDS_LIB mstr_standard
J 0
(-3350 3400);
DISPLAY 0.787234 (-3350 3400);
PAINT MONO (-3350 3400);
DISPLAY INVISIBLE (-3350 3400);
FORCEPROP 1 LAST BODY_TYPE PLUMBING
J 0
(-3350 3350);
DISPLAY 1.234043 (-3350 3350);
PAINT GREEN (-3350 3350);
DISPLAY INVISIBLE (-3350 3350);
FORCEPROP 1 LAST HDL_TAP TRUE
J 0
(-3025 3275);
DISPLAY 1.234043 (-3025 3275);
PAINT GREEN (-3025 3275);
DISPLAY INVISIBLE (-3025 3275);
FORCEPROP 1 LAST PATH I158
J 0
(-3350 3400);
DISPLAY 0.936170 (-3350 3400);
PAINT GREEN (-3350 3400);
DISPLAY INVISIBLE (-3350 3400);
FORCEADD TAP..6
(-3350 3350);
FORCEPROP 3 LASTPIN (-3300 3350) SIG_NAME M_H_CS_N<2>
J 0
(-3290 3360);
DISPLAY 0.659574 (-3290 3360);
PAINT MONO (-3290 3360);
DISPLAY INVISIBLE (-3290 3360);
FORCEPROP 1 LASTPIN (-3300 3350) BN 2
J 0
(-3350 3360);
DISPLAY 0.617021 (-3350 3360);
PAINT PINK (-3350 3360);
FORCEPROP 2 LAST CDS_LIB mstr_standard
J 0
(-3350 3350);
DISPLAY 0.787234 (-3350 3350);
PAINT MONO (-3350 3350);
DISPLAY INVISIBLE (-3350 3350);
FORCEPROP 1 LAST BODY_TYPE PLUMBING
J 0
(-3350 3300);
DISPLAY 1.234043 (-3350 3300);
PAINT GREEN (-3350 3300);
DISPLAY INVISIBLE (-3350 3300);
FORCEPROP 1 LAST HDL_TAP TRUE
J 0
(-3025 3225);
DISPLAY 1.234043 (-3025 3225);
PAINT GREEN (-3025 3225);
DISPLAY INVISIBLE (-3025 3225);
FORCEPROP 1 LAST PATH I159
J 0
(-3350 3350);
DISPLAY 0.936170 (-3350 3350);
PAINT GREEN (-3350 3350);
DISPLAY INVISIBLE (-3350 3350);
FORCEADD PVTT_GHJ..1
(-1300 2700);
FORCEPROP 3 LASTPIN (-1300 2650) SIG_NAME PVTT_GHJ\g
J 0
(-1290 2660);
DISPLAY 0.659574 (-1290 2660);
PAINT MONO (-1290 2660);
DISPLAY INVISIBLE (-1290 2660);
FORCEPROP 1 LAST VOLTAGE 0.6V
J 0
(-1345 2657);
DISPLAY 0.340426 (-1345 2657);
PAINT SKYBLUE (-1345 2657);
DISPLAY INVISIBLE (-1345 2657);
FORCEPROP 2 LAST BOM_COST MEM
J 0
(-1300 2705);
PAINT ORANGE (-1300 2705);
DISPLAY INVISIBLE (-1300 2705);
FORCEPROP 2 LAST CDS_LIB mstr_symbols
J 0
(-1300 2700);
PAINT ORANGE (-1300 2700);
DISPLAY INVISIBLE (-1300 2700);
FORCEPROP 1 LAST BODY_TYPE PLUMBING
J 0
(-1345 2657);
DISPLAY 0.340426 (-1345 2657);
PAINT GREEN (-1345 2657);
DISPLAY INVISIBLE (-1345 2657);
FORCEPROP 1 LAST PATH I16
J 0
(-1250 2725);
DISPLAY 0.872340 (-1250 2725);
PAINT AQUA (-1250 2725);
DISPLAY INVISIBLE (-1250 2725);
FORCEPROP 2 LAST ROOM DDR4_CH_H
J 0
(-1300 2800);
DISPLAY 0.787234 (-1300 2800);
PAINT ORANGE (-1300 2800);
DISPLAY INVISIBLE (-1300 2800);
FORCEPROP 1 LAST HDL_POWER PVTT_GHJ
J 1
(-1300 2750);
DISPLAY 0.872340 (-1300 2750);
PAINT GREEN (-1300 2750);
DISPLAY INVISIBLE (-1300 2750);
FORCEADD TAP..6
(-3350 3300);
FORCEPROP 3 LASTPIN (-3300 3300) SIG_NAME M_H_CS_N<1>
J 0
(-3290 3310);
DISPLAY 0.659574 (-3290 3310);
PAINT MONO (-3290 3310);
DISPLAY INVISIBLE (-3290 3310);
FORCEPROP 1 LASTPIN (-3300 3300) BN 1
J 0
(-3350 3310);
DISPLAY 0.617021 (-3350 3310);
PAINT PINK (-3350 3310);
FORCEPROP 2 LAST CDS_LIB mstr_standard
J 0
(-3350 3300);
DISPLAY 0.787234 (-3350 3300);
PAINT MONO (-3350 3300);
DISPLAY INVISIBLE (-3350 3300);
FORCEPROP 1 LAST BODY_TYPE PLUMBING
J 0
(-3350 3250);
DISPLAY 1.234043 (-3350 3250);
PAINT GREEN (-3350 3250);
DISPLAY INVISIBLE (-3350 3250);
FORCEPROP 1 LAST HDL_TAP TRUE
J 0
(-3025 3175);
DISPLAY 1.234043 (-3025 3175);
PAINT GREEN (-3025 3175);
DISPLAY INVISIBLE (-3025 3175);
FORCEPROP 1 LAST PATH I160
J 0
(-3350 3300);
DISPLAY 0.936170 (-3350 3300);
PAINT GREEN (-3350 3300);
DISPLAY INVISIBLE (-3350 3300);
FORCEADD TAP..6
(-3350 3250);
FORCEPROP 3 LASTPIN (-3300 3250) SIG_NAME M_H_CS_N<0>
J 0
(-3290 3260);
DISPLAY 0.659574 (-3290 3260);
PAINT MONO (-3290 3260);
DISPLAY INVISIBLE (-3290 3260);
FORCEPROP 1 LASTPIN (-3300 3250) BN 0
J 0
(-3350 3260);
DISPLAY 0.617021 (-3350 3260);
PAINT PINK (-3350 3260);
FORCEPROP 2 LAST CDS_LIB mstr_standard
J 0
(-3350 3250);
DISPLAY 0.787234 (-3350 3250);
PAINT MONO (-3350 3250);
DISPLAY INVISIBLE (-3350 3250);
FORCEPROP 1 LAST BODY_TYPE PLUMBING
J 0
(-3350 3200);
DISPLAY 1.234043 (-3350 3200);
PAINT GREEN (-3350 3200);
DISPLAY INVISIBLE (-3350 3200);
FORCEPROP 1 LAST HDL_TAP TRUE
J 0
(-3025 3125);
DISPLAY 1.234043 (-3025 3125);
PAINT GREEN (-3025 3125);
DISPLAY INVISIBLE (-3025 3125);
FORCEPROP 1 LAST PATH I161
J 0
(-3350 3250);
DISPLAY 0.936170 (-3350 3250);
PAINT GREEN (-3350 3250);
DISPLAY INVISIBLE (-3350 3250);
FORCEADD TAP..6
(-3350 3150);
FORCEPROP 3 LASTPIN (-3300 3150) SIG_NAME M_H_CKE<1>
J 0
(-3290 3160);
DISPLAY 0.659574 (-3290 3160);
PAINT MONO (-3290 3160);
DISPLAY INVISIBLE (-3290 3160);
FORCEPROP 1 LASTPIN (-3300 3150) BN 1
J 0
(-3350 3160);
DISPLAY 0.617021 (-3350 3160);
PAINT PINK (-3350 3160);
FORCEPROP 2 LAST CDS_LIB mstr_standard
J 0
(-3350 3150);
DISPLAY 0.787234 (-3350 3150);
PAINT MONO (-3350 3150);
DISPLAY INVISIBLE (-3350 3150);
FORCEPROP 1 LAST BODY_TYPE PLUMBING
J 0
(-3350 3100);
DISPLAY 1.234043 (-3350 3100);
PAINT GREEN (-3350 3100);
DISPLAY INVISIBLE (-3350 3100);
FORCEPROP 1 LAST HDL_TAP TRUE
J 0
(-3025 3025);
DISPLAY 1.234043 (-3025 3025);
PAINT GREEN (-3025 3025);
DISPLAY INVISIBLE (-3025 3025);
FORCEPROP 1 LAST PATH I162
J 0
(-3350 3150);
DISPLAY 0.936170 (-3350 3150);
PAINT GREEN (-3350 3150);
DISPLAY INVISIBLE (-3350 3150);
FORCEADD TAP..6
(-3350 3100);
FORCEPROP 3 LASTPIN (-3300 3100) SIG_NAME M_H_CKE<0>
J 0
(-3290 3110);
DISPLAY 0.659574 (-3290 3110);
PAINT MONO (-3290 3110);
DISPLAY INVISIBLE (-3290 3110);
FORCEPROP 1 LASTPIN (-3300 3100) BN 0
J 0
(-3350 3110);
DISPLAY 0.617021 (-3350 3110);
PAINT PINK (-3350 3110);
FORCEPROP 2 LAST CDS_LIB mstr_standard
J 0
(-3350 3100);
DISPLAY 0.787234 (-3350 3100);
PAINT MONO (-3350 3100);
DISPLAY INVISIBLE (-3350 3100);
FORCEPROP 1 LAST BODY_TYPE PLUMBING
J 0
(-3350 3050);
DISPLAY 1.234043 (-3350 3050);
PAINT GREEN (-3350 3050);
DISPLAY INVISIBLE (-3350 3050);
FORCEPROP 1 LAST HDL_TAP TRUE
J 0
(-3025 2975);
DISPLAY 1.234043 (-3025 2975);
PAINT GREEN (-3025 2975);
DISPLAY INVISIBLE (-3025 2975);
FORCEPROP 1 LAST PATH I163
J 0
(-3350 3100);
DISPLAY 0.936170 (-3350 3100);
PAINT GREEN (-3350 3100);
DISPLAY INVISIBLE (-3350 3100);
FORCEADD TAP..6
(-3350 3000);
FORCEPROP 3 LASTPIN (-3300 3000) SIG_NAME M_H_ODT<1>
J 0
(-3290 3010);
DISPLAY 0.659574 (-3290 3010);
PAINT MONO (-3290 3010);
DISPLAY INVISIBLE (-3290 3010);
FORCEPROP 1 LASTPIN (-3300 3000) BN 1
J 0
(-3350 3010);
DISPLAY 0.617021 (-3350 3010);
PAINT PINK (-3350 3010);
FORCEPROP 2 LAST CDS_LIB mstr_standard
J 0
(-3350 3000);
DISPLAY 0.787234 (-3350 3000);
PAINT MONO (-3350 3000);
DISPLAY INVISIBLE (-3350 3000);
FORCEPROP 1 LAST BODY_TYPE PLUMBING
J 0
(-3350 2950);
DISPLAY 1.234043 (-3350 2950);
PAINT GREEN (-3350 2950);
DISPLAY INVISIBLE (-3350 2950);
FORCEPROP 1 LAST HDL_TAP TRUE
J 0
(-3025 2875);
DISPLAY 1.234043 (-3025 2875);
PAINT GREEN (-3025 2875);
DISPLAY INVISIBLE (-3025 2875);
FORCEPROP 1 LAST PATH I164
J 0
(-3350 3000);
DISPLAY 0.936170 (-3350 3000);
PAINT GREEN (-3350 3000);
DISPLAY INVISIBLE (-3350 3000);
FORCEADD OFFPAGE..1
(-4000 3450);
FORCEPROP 2 LAST $XR0 58 
J 0
(-4251 3450);
DISPLAY 0.638298 (-4251 3450);
PAINT MONO (-4251 3450);
FORCEPROP 2 LAST $XR1 80 
J 0
(-4341 3450);
DISPLAY 0.638298 (-4341 3450);
PAINT MONO (-4341 3450);
FORCEPROP 2 LAST CDS_LIB mstr_standard
J 0
(-4000 3450);
DISPLAY 0.787234 (-4000 3450);
PAINT MONO (-4000 3450);
DISPLAY INVISIBLE (-4000 3450);
FORCEPROP 1 LAST OFFPAGE TRUE
J 0
(-3675 3325);
DISPLAY 0.936170 (-3675 3325);
PAINT GREEN (-3675 3325);
DISPLAY INVISIBLE (-3675 3325);
FORCEPROP 1 LAST COMMENT_BODY TRUE
J 0
(-3875 3350);
DISPLAY 0.936170 (-3875 3350);
PAINT GREEN (-3875 3350);
DISPLAY INVISIBLE (-3875 3350);
FORCEPROP 2 LAST PATH I165
J 0
(-3950 3525);
DISPLAY 0.787234 (-3950 3525);
PAINT MONO (-3950 3525);
DISPLAY INVISIBLE (-3950 3525);
FORCEADD OFFPAGE..1
(-4000 3200);
FORCEPROP 2 LAST $XR0 58 
J 0
(-4251 3200);
DISPLAY 0.638298 (-4251 3200);
PAINT MONO (-4251 3200);
FORCEPROP 2 LAST $XR1 80 
J 0
(-4341 3200);
DISPLAY 0.638298 (-4341 3200);
PAINT MONO (-4341 3200);
FORCEPROP 2 LAST CDS_LIB mstr_standard
J 0
(-4000 3200);
DISPLAY 0.787234 (-4000 3200);
PAINT MONO (-4000 3200);
DISPLAY INVISIBLE (-4000 3200);
FORCEPROP 1 LAST OFFPAGE TRUE
J 0
(-3675 3075);
DISPLAY 0.936170 (-3675 3075);
PAINT GREEN (-3675 3075);
DISPLAY INVISIBLE (-3675 3075);
FORCEPROP 1 LAST COMMENT_BODY TRUE
J 0
(-3875 3100);
DISPLAY 0.936170 (-3875 3100);
PAINT GREEN (-3875 3100);
DISPLAY INVISIBLE (-3875 3100);
FORCEPROP 2 LAST PATH I166
J 0
(-3950 3275);
DISPLAY 0.787234 (-3950 3275);
PAINT MONO (-3950 3275);
DISPLAY INVISIBLE (-3950 3275);
FORCEADD OFFPAGE..1
(-4000 3050);
FORCEPROP 2 LAST $XR0 58 
J 0
(-4251 3050);
DISPLAY 0.638298 (-4251 3050);
PAINT MONO (-4251 3050);
FORCEPROP 2 LAST $XR1 80 
J 0
(-4341 3050);
DISPLAY 0.638298 (-4341 3050);
PAINT MONO (-4341 3050);
FORCEPROP 2 LAST CDS_LIB mstr_standard
J 0
(-4000 3050);
DISPLAY 0.787234 (-4000 3050);
PAINT MONO (-4000 3050);
DISPLAY INVISIBLE (-4000 3050);
FORCEPROP 1 LAST OFFPAGE TRUE
J 0
(-3675 2925);
DISPLAY 0.936170 (-3675 2925);
PAINT GREEN (-3675 2925);
DISPLAY INVISIBLE (-3675 2925);
FORCEPROP 1 LAST COMMENT_BODY TRUE
J 0
(-3875 2950);
DISPLAY 0.936170 (-3875 2950);
PAINT GREEN (-3875 2950);
DISPLAY INVISIBLE (-3875 2950);
FORCEPROP 2 LAST PATH I167
J 0
(-3950 3125);
DISPLAY 0.787234 (-3950 3125);
PAINT MONO (-3950 3125);
DISPLAY INVISIBLE (-3950 3125);
FORCEADD TAP..6
(-3350 2950);
FORCEPROP 3 LASTPIN (-3300 2950) SIG_NAME M_H_ODT<0>
J 0
(-3290 2960);
DISPLAY 0.659574 (-3290 2960);
PAINT MONO (-3290 2960);
DISPLAY INVISIBLE (-3290 2960);
FORCEPROP 1 LASTPIN (-3300 2950) BN 0
J 0
(-3350 2960);
DISPLAY 0.617021 (-3350 2960);
PAINT PINK (-3350 2960);
FORCEPROP 2 LAST CDS_LIB mstr_standard
J 0
(-3350 2950);
DISPLAY 0.787234 (-3350 2950);
PAINT MONO (-3350 2950);
DISPLAY INVISIBLE (-3350 2950);
FORCEPROP 1 LAST BODY_TYPE PLUMBING
J 0
(-3350 2900);
DISPLAY 1.234043 (-3350 2900);
PAINT GREEN (-3350 2900);
DISPLAY INVISIBLE (-3350 2900);
FORCEPROP 1 LAST HDL_TAP TRUE
J 0
(-3025 2825);
DISPLAY 1.234043 (-3025 2825);
PAINT GREEN (-3025 2825);
DISPLAY INVISIBLE (-3025 2825);
FORCEPROP 1 LAST PATH I168
J 0
(-3350 2950);
DISPLAY 0.936170 (-3350 2950);
PAINT GREEN (-3350 2950);
DISPLAY INVISIBLE (-3350 2950);
FORCEADD SCONN288_H44441004..4
(-450 2000);
FORCEPROP 1 LAST LOCATION J1G2
J 0
(-900 3100);
DISPLAY 0.617021 (-900 3100);
PAINT AQUA (-900 3100);
FORCEPROP 1 LAST PART_NUMBER H44441-004
J 0
(-900 950);
DISPLAY 0.617021 (-900 950);
PAINT BLUE (-900 950);
FORCEPROP 1 LAST MATERIAL SCONN
J 0
(-900 3050);
DISPLAY 0.617021 (-900 3050);
PAINT SKYBLUE (-900 3050);
FORCEPROP 2 LASTPIN (-950 2550) $PN 77
J 2
(-960 2560);
DISPLAY 0.617021 (-960 2560);
PAINT ORANGE (-960 2560);
FORCEPROP 2 LASTPIN (-950 2500) $PN 221
J 2
(-960 2510);
DISPLAY 0.617021 (-960 2510);
PAINT ORANGE (-960 2510);
FORCEPROP 2 LASTPIN (-950 2850) $PN 142
J 2
(-960 2860);
DISPLAY 0.617021 (-960 2860);
PAINT ORANGE (-960 2860);
FORCEPROP 2 LASTPIN (-950 2800) $PN 143
J 2
(-960 2810);
DISPLAY 0.617021 (-960 2810);
PAINT ORANGE (-960 2810);
FORCEPROP 2 LASTPIN (-950 2750) $PN 288
J 2
(-960 2760);
DISPLAY 0.617021 (-960 2760);
PAINT ORANGE (-960 2760);
FORCEPROP 2 LASTPIN (-950 2700) $PN 286
J 2
(-960 2710);
DISPLAY 0.617021 (-960 2710);
PAINT ORANGE (-960 2710);
FORCEPROP 2 LASTPIN (-950 2650) $PN 287
J 2
(-960 2660);
DISPLAY 0.617021 (-960 2660);
PAINT ORANGE (-960 2660);
FORCEPROP 2 LASTPIN (-950 2400) $PN 59
J 2
(-960 2410);
DISPLAY 0.617021 (-960 2410);
PAINT ORANGE (-960 2410);
FORCEPROP 2 LASTPIN (-950 2350) $PN 61
J 2
(-960 2360);
DISPLAY 0.617021 (-960 2360);
PAINT ORANGE (-960 2360);
FORCEPROP 2 LASTPIN (-950 2300) $PN 64
J 2
(-960 2310);
DISPLAY 0.617021 (-960 2310);
PAINT ORANGE (-960 2310);
FORCEPROP 2 LASTPIN (-950 2250) $PN 67
J 2
(-960 2260);
DISPLAY 0.617021 (-960 2260);
PAINT ORANGE (-960 2260);
FORCEPROP 2 LASTPIN (-950 2200) $PN 70
J 2
(-960 2210);
DISPLAY 0.617021 (-960 2210);
PAINT ORANGE (-960 2210);
FORCEPROP 2 LASTPIN (-950 2150) $PN 73
J 2
(-960 2160);
DISPLAY 0.617021 (-960 2160);
PAINT ORANGE (-960 2160);
FORCEPROP 2 LASTPIN (-950 2100) $PN 76
J 2
(-960 2110);
DISPLAY 0.617021 (-960 2110);
PAINT ORANGE (-960 2110);
FORCEPROP 2 LASTPIN (-950 2050) $PN 80
J 2
(-960 2060);
DISPLAY 0.617021 (-960 2060);
PAINT ORANGE (-960 2060);
FORCEPROP 2 LASTPIN (-950 2000) $PN 83
J 2
(-960 2010);
DISPLAY 0.617021 (-960 2010);
PAINT ORANGE (-960 2010);
FORCEPROP 2 LASTPIN (-950 1950) $PN 85
J 2
(-960 1960);
DISPLAY 0.617021 (-960 1960);
PAINT ORANGE (-960 1960);
FORCEPROP 2 LASTPIN (-950 1900) $PN 88
J 2
(-960 1910);
DISPLAY 0.617021 (-960 1910);
PAINT ORANGE (-960 1910);
FORCEPROP 2 LASTPIN (-950 1850) $PN 90
J 2
(-960 1860);
DISPLAY 0.617021 (-960 1860);
PAINT ORANGE (-960 1860);
FORCEPROP 2 LASTPIN (-950 1800) $PN 92
J 2
(-960 1810);
DISPLAY 0.617021 (-960 1810);
PAINT ORANGE (-960 1810);
FORCEPROP 2 LASTPIN (-950 1750) $PN 204
J 2
(-960 1760);
DISPLAY 0.617021 (-960 1760);
PAINT ORANGE (-960 1760);
FORCEPROP 2 LASTPIN (-950 1700) $PN 206
J 2
(-960 1710);
DISPLAY 0.617021 (-960 1710);
PAINT ORANGE (-960 1710);
FORCEPROP 2 LASTPIN (-950 1650) $PN 209
J 2
(-960 1660);
DISPLAY 0.617021 (-960 1660);
PAINT ORANGE (-960 1660);
FORCEPROP 2 LASTPIN (-950 1600) $PN 212
J 2
(-960 1610);
DISPLAY 0.617021 (-960 1610);
PAINT ORANGE (-960 1610);
FORCEPROP 2 LASTPIN (-950 1550) $PN 215
J 2
(-960 1560);
DISPLAY 0.617021 (-960 1560);
PAINT ORANGE (-960 1560);
FORCEPROP 2 LASTPIN (-950 1500) $PN 217
J 2
(-960 1510);
DISPLAY 0.617021 (-960 1510);
PAINT ORANGE (-960 1510);
FORCEPROP 2 LASTPIN (-950 1450) $PN 220
J 2
(-960 1460);
DISPLAY 0.617021 (-960 1460);
PAINT ORANGE (-960 1460);
FORCEPROP 2 LASTPIN (-950 1400) $PN 223
J 2
(-960 1410);
DISPLAY 0.617021 (-960 1410);
PAINT ORANGE (-960 1410);
FORCEPROP 2 LASTPIN (-950 1350) $PN 226
J 2
(-960 1360);
DISPLAY 0.617021 (-960 1360);
PAINT ORANGE (-960 1360);
FORCEPROP 2 LASTPIN (-950 1300) $PN 229
J 2
(-960 1310);
DISPLAY 0.617021 (-960 1310);
PAINT ORANGE (-960 1310);
FORCEPROP 2 LASTPIN (-950 1250) $PN 231
J 2
(-960 1260);
DISPLAY 0.617021 (-960 1260);
PAINT ORANGE (-960 1260);
FORCEPROP 2 LASTPIN (-950 1200) $PN 233
J 2
(-960 1210);
DISPLAY 0.617021 (-960 1210);
PAINT ORANGE (-960 1210);
FORCEPROP 2 LASTPIN (-950 1150) $PN 236
J 2
(-960 1160);
DISPLAY 0.617021 (-960 1160);
PAINT ORANGE (-960 1160);
FORCEPROP 2 LASTPIN (50 2850) $PN 1
J 0
(60 2860);
DISPLAY 0.617021 (60 2860);
PAINT ORANGE (60 2860);
FORCEPROP 2 LASTPIN (50 2800) $PN 145
J 0
(60 2810);
DISPLAY 0.617021 (60 2810);
PAINT ORANGE (60 2810);
FORCEPROP 1 LAST PACK_TYPE PIP
J 0
(-900 3150);
PAINT SKYBLUE (-900 3150);
DISPLAY INVISIBLE (-900 3150);
FORCEPROP 2 LAST BOM_COST MEM
J 0
(-450 2000);
PAINT ORANGE (-450 2000);
DISPLAY INVISIBLE (-450 2000);
FORCEPROP 2 LAST CDS_LIB mstr_sconn
J 0
(-450 2000);
PAINT ORANGE (-450 2000);
DISPLAY INVISIBLE (-450 2000);
FORCEPROP 2 LAST SEC_TYPE PIP
J 0
(-900 3150);
DISPLAY 1.021277 (-900 3150);
PAINT ORANGE (-900 3150);
DISPLAY INVISIBLE (-900 3150);
FORCEPROP 2 LAST SEC 4
J 0
(-900 3150);
DISPLAY 0.680851 (-900 3150);
PAINT MONO (-900 3150);
DISPLAY INVISIBLE (-900 3150);
FORCEPROP 2 LAST CDS_LOCATION J1G2
J 0
(-900 3100);
DISPLAY 0.617021 (-900 3100);
PAINT AQUA (-900 3100);
DISPLAY INVISIBLE (-900 3100);
FORCEPROP 1 LAST PATH I169
J 0
(-450 3050);
PAINT GREEN (-450 3050);
DISPLAY INVISIBLE (-450 3050);
FORCEPROP 2 LAST ROOM DDR4_CH_H
J 0
(-450 2000);
PAINT ORANGE (-450 2000);
DISPLAY INVISIBLE (-450 2000);
FORCEADD TAP..6
R 2
(850 4600);
FORCEPROP 3 LASTPIN (800 4600) SIG_NAME M_H_DQS_DN<12>
J 0
(810 4610);
DISPLAY 0.659574 (810 4610);
PAINT MONO (810 4610);
DISPLAY INVISIBLE (810 4610);
FORCEPROP 1 LASTPIN (800 4600) BN 12
J 2
(850 4610);
DISPLAY 0.617021 (850 4610);
PAINT PINK (850 4610);
FORCEPROP 2 LAST CDS_LIB mstr_standard
J 0
(850 4600);
DISPLAY 0.787234 (850 4600);
PAINT MONO (850 4600);
DISPLAY INVISIBLE (850 4600);
FORCEPROP 1 LAST BODY_TYPE PLUMBING
J 2
(850 4550);
DISPLAY 1.234043 (850 4550);
PAINT GREEN (850 4550);
DISPLAY INVISIBLE (850 4550);
FORCEPROP 1 LAST HDL_TAP TRUE
J 2
(525 4475);
DISPLAY 1.234043 (525 4475);
PAINT GREEN (525 4475);
DISPLAY INVISIBLE (525 4475);
FORCEPROP 1 LAST PATH I17
J 2
(850 4600);
DISPLAY 0.936170 (850 4600);
PAINT GREEN (850 4600);
DISPLAY INVISIBLE (850 4600);
FORCEADD GND..1
R 2
(2450 1100);
FORCEPROP 3 LASTPIN (2450 1150) SIG_NAME GND\g
J 0
(2460 1160);
DISPLAY 0.659574 (2460 1160);
PAINT MONO (2460 1160);
DISPLAY INVISIBLE (2460 1160);
FORCEPROP 1 LAST VOLTAGE 0
J 0
(2450 1100);
PAINT SKYBLUE (2450 1100);
DISPLAY INVISIBLE (2450 1100);
FORCEPROP 2 LAST CDS_LIB mstr_symbols
J 0
(2450 1100);
DISPLAY 0.787234 (2450 1100);
PAINT MONO (2450 1100);
DISPLAY INVISIBLE (2450 1100);
FORCEPROP 1 LAST SIZE 1B
J 2
(2375 1050);
DISPLAY 1.170213 (2375 1050);
PAINT GREEN (2375 1050);
DISPLAY INVISIBLE (2375 1050);
FORCEPROP 2 LAST BOM_COST MEM
J 0
(2450 1105);
PAINT ORANGE (2450 1105);
DISPLAY INVISIBLE (2450 1105);
FORCEPROP 1 LAST BODY_TYPE PLUMBING
J 2
(2495 1057);
DISPLAY 0.340426 (2495 1057);
PAINT GREEN (2495 1057);
DISPLAY INVISIBLE (2495 1057);
FORCEPROP 1 LAST PATH I170
J 2
(2375 1100);
DISPLAY 1.404255 (2375 1100);
PAINT GREEN (2375 1100);
DISPLAY INVISIBLE (2375 1100);
FORCEPROP 2 LAST ROOM DDR4_CH_H
J 0
(2450 1105);
PAINT ORANGE (2450 1105);
DISPLAY INVISIBLE (2450 1105);
FORCEPROP 1 LAST HDL_POWER GND
J 2
(2450 1250);
DISPLAY 0.553191 (2450 1250);
PAINT GREEN (2450 1250);
DISPLAY INVISIBLE (2450 1250);
FORCEADD OFFPAGE..1
(-4000 1850);
FORCEPROP 2 LAST $XR0 99 
J 0
(-4251 1850);
DISPLAY 0.638298 (-4251 1850);
PAINT MONO (-4251 1850);
FORCEPROP 2 LAST $XR1 77 
J 0
(-4341 1850);
DISPLAY 0.638298 (-4341 1850);
PAINT MONO (-4341 1850);
FORCEPROP 2 LAST $XR2 78 
J 0
(-4431 1850);
DISPLAY 0.638298 (-4431 1850);
PAINT MONO (-4431 1850);
FORCEPROP 2 LAST $XR3 80 
J 0
(-4521 1850);
DISPLAY 0.638298 (-4521 1850);
PAINT MONO (-4521 1850);
FORCEPROP 2 LAST $XR4 81 
J 0
(-4611 1850);
DISPLAY 0.638298 (-4611 1850);
PAINT MONO (-4611 1850);
FORCEPROP 2 LAST $XR5 82 
J 0
(-4701 1850);
DISPLAY 0.638298 (-4701 1850);
PAINT MONO (-4701 1850);
FORCEPROP 2 LAST CDS_LIB mstr_standard
J 0
(-4000 1850);
DISPLAY 0.787234 (-4000 1850);
PAINT MONO (-4000 1850);
DISPLAY INVISIBLE (-4000 1850);
FORCEPROP 1 LAST OFFPAGE TRUE
J 0
(-3675 1725);
DISPLAY 0.936170 (-3675 1725);
PAINT GREEN (-3675 1725);
DISPLAY INVISIBLE (-3675 1725);
FORCEPROP 1 LAST COMMENT_BODY TRUE
J 0
(-3875 1750);
DISPLAY 0.936170 (-3875 1750);
PAINT GREEN (-3875 1750);
DISPLAY INVISIBLE (-3875 1750);
FORCEPROP 2 LAST PATH I171
J 0
(-4275 1900);
DISPLAY 0.787234 (-4275 1900);
PAINT ORANGE (-4275 1900);
DISPLAY INVISIBLE (-4275 1900);
FORCEADD OFFPAGE..6
(-4000 1900);
FORCEPROP 2 LAST $XR0 77 
J 0
(-4249 1900);
DISPLAY 0.638298 (-4249 1900);
PAINT MONO (-4249 1900);
FORCEPROP 2 LAST $XR1 78 
J 0
(-4339 1900);
DISPLAY 0.638298 (-4339 1900);
PAINT MONO (-4339 1900);
FORCEPROP 2 LAST $XR2 80 
J 0
(-4429 1900);
DISPLAY 0.638298 (-4429 1900);
PAINT MONO (-4429 1900);
FORCEPROP 2 LAST $XR3 81 
J 0
(-4519 1900);
DISPLAY 0.638298 (-4519 1900);
PAINT MONO (-4519 1900);
FORCEPROP 2 LAST $XR4 82 
J 0
(-4609 1900);
DISPLAY 0.638298 (-4609 1900);
PAINT MONO (-4609 1900);
FORCEPROP 2 LAST $XR5 99 
J 0
(-4699 1900);
DISPLAY 0.638298 (-4699 1900);
PAINT MONO (-4699 1900);
FORCEPROP 2 LASTPIN (-3950 1900) SIG_NAME SMB_DDR_GHJ_VPP_SDA
J 0
(-3910 1910);
DISPLAY 0.617021 (-3910 1910);
PAINT ORANGE (-3910 1910);
FORCEPROP 2 LAST CDS_LIB mstr_standard
J 0
(-4000 1900);
DISPLAY 0.787234 (-4000 1900);
PAINT MONO (-4000 1900);
DISPLAY INVISIBLE (-4000 1900);
FORCEPROP 1 LAST OFFPAGE TRUE
J 0
(-3675 1775);
DISPLAY 0.936170 (-3675 1775);
PAINT GREEN (-3675 1775);
DISPLAY INVISIBLE (-3675 1775);
FORCEPROP 1 LAST COMMENT_BODY TRUE
J 0
(-3900 1825);
DISPLAY 0.936170 (-3900 1825);
PAINT GREEN (-3900 1825);
DISPLAY INVISIBLE (-3900 1825);
FORCEPROP 2 LAST PATH I172
J 0
(-4325 1950);
DISPLAY 0.787234 (-4325 1950);
PAINT ORANGE (-4325 1950);
DISPLAY INVISIBLE (-4325 1950);
FORCEADD OFFPAGE..1
(-4700 1750);
FORCEPROP 2 LAST $XR0 100 
J 0
(-4952 1750);
DISPLAY 0.638298 (-4952 1750);
PAINT MONO (-4952 1750);
FORCEPROP 2 LAST $XR1 80 
J 0
(-5042 1750);
DISPLAY 0.638298 (-5042 1750);
PAINT MONO (-5042 1750);
FORCEPROP 2 LAST CDS_LIB mstr_standard
J 0
(-4700 1750);
DISPLAY 0.787234 (-4700 1750);
PAINT MONO (-4700 1750);
DISPLAY INVISIBLE (-4700 1750);
FORCEPROP 1 LAST OFFPAGE TRUE
J 0
(-4375 1625);
DISPLAY 0.936170 (-4375 1625);
PAINT GREEN (-4375 1625);
DISPLAY INVISIBLE (-4375 1625);
FORCEPROP 1 LAST COMMENT_BODY TRUE
J 0
(-4575 1650);
DISPLAY 0.936170 (-4575 1650);
PAINT GREEN (-4575 1650);
DISPLAY INVISIBLE (-4575 1650);
FORCEPROP 2 LAST PATH I173
J 0
(-4950 1800);
DISPLAY 0.787234 (-4950 1800);
PAINT ORANGE (-4950 1800);
DISPLAY INVISIBLE (-4950 1800);
FORCEADD GND..1
R 2
(-5200 1900);
FORCEPROP 3 LASTPIN (-5200 1950) SIG_NAME GND\g
J 0
(-5190 1960);
DISPLAY 0.659574 (-5190 1960);
PAINT MONO (-5190 1960);
DISPLAY INVISIBLE (-5190 1960);
FORCEPROP 1 LAST VOLTAGE 0
J 0
(-5200 1900);
PAINT SKYBLUE (-5200 1900);
DISPLAY INVISIBLE (-5200 1900);
FORCEPROP 2 LAST CDS_LIB mstr_symbols
J 0
(-5200 1900);
DISPLAY 0.787234 (-5200 1900);
PAINT MONO (-5200 1900);
DISPLAY INVISIBLE (-5200 1900);
FORCEPROP 1 LAST SIZE 1B
J 2
(-5275 1850);
DISPLAY 1.170213 (-5275 1850);
PAINT GREEN (-5275 1850);
DISPLAY INVISIBLE (-5275 1850);
FORCEPROP 2 LAST BOM_COST MEM
J 0
(-5200 1905);
PAINT ORANGE (-5200 1905);
DISPLAY INVISIBLE (-5200 1905);
FORCEPROP 1 LAST BODY_TYPE PLUMBING
J 2
(-5155 1857);
DISPLAY 0.340426 (-5155 1857);
PAINT GREEN (-5155 1857);
DISPLAY INVISIBLE (-5155 1857);
FORCEPROP 1 LAST PATH I175
J 2
(-5275 1900);
DISPLAY 1.404255 (-5275 1900);
PAINT GREEN (-5275 1900);
DISPLAY INVISIBLE (-5275 1900);
FORCEPROP 2 LAST ROOM DDR4_CH_H
J 0
(-5200 1905);
PAINT ORANGE (-5200 1905);
DISPLAY INVISIBLE (-5200 1905);
FORCEPROP 1 LAST HDL_POWER GND
J 2
(-5200 2050);
DISPLAY 0.553191 (-5200 2050);
PAINT GREEN (-5200 2050);
DISPLAY INVISIBLE (-5200 2050);
FORCEADD OFFPAGE..5
(-4325 2600);
FORCEPROP 2 LAST $XR0 43 
J 0
(-4579 2600);
DISPLAY 0.638298 (-4579 2600);
PAINT MONO (-4579 2600);
FORCEPROP 2 LAST $XR1 44 
J 0
(-4669 2600);
DISPLAY 0.638298 (-4669 2600);
PAINT MONO (-4669 2600);
FORCEPROP 2 LAST $XR2 45 
J 0
(-4759 2600);
DISPLAY 0.638298 (-4759 2600);
PAINT MONO (-4759 2600);
FORCEPROP 2 LAST $XR3 46 
J 0
(-4849 2600);
DISPLAY 0.638298 (-4849 2600);
PAINT MONO (-4849 2600);
FORCEPROP 2 LAST $XR4 47 
J 0
(-4939 2600);
DISPLAY 0.638298 (-4939 2600);
PAINT MONO (-4939 2600);
FORCEPROP 2 LAST $XR5 48 
J 0
(-5029 2600);
DISPLAY 0.638298 (-5029 2600);
PAINT MONO (-5029 2600);
FORCEPROP 2 LAST $XR6 49 
J 0
(-5119 2600);
DISPLAY 0.638298 (-5119 2600);
PAINT MONO (-5119 2600);
FORCEPROP 2 LAST $XR7 50 
J 0
(-5209 2600);
DISPLAY 0.638298 (-5209 2600);
PAINT MONO (-5209 2600);
FORCEPROP 2 LAST $XR8 51 
J 0
(-5299 2600);
DISPLAY 0.638298 (-5299 2600);
PAINT MONO (-5299 2600);
FORCEPROP 2 LAST $XR9 52 
J 0
(-4579 2564);
DISPLAY 0.638298 (-4579 2564);
PAINT MONO (-4579 2564);
FORCEPROP 2 LAST $XR10 53 
J 0
(-4669 2564);
DISPLAY 0.638298 (-4669 2564);
PAINT MONO (-4669 2564);
FORCEPROP 2 LAST $XR11 54 
J 0
(-4759 2564);
DISPLAY 0.638298 (-4759 2564);
PAINT MONO (-4759 2564);
FORCEPROP 2 LAST $XR12 77 
J 0
(-4849 2564);
DISPLAY 0.638298 (-4849 2564);
PAINT MONO (-4849 2564);
FORCEPROP 2 LAST $XR13 78 
J 0
(-4939 2564);
DISPLAY 0.638298 (-4939 2564);
PAINT MONO (-4939 2564);
FORCEPROP 2 LAST $XR14 80 
J 0
(-5029 2564);
DISPLAY 0.638298 (-5029 2564);
PAINT MONO (-5029 2564);
FORCEPROP 2 LAST $XR15 81 
J 0
(-5119 2564);
DISPLAY 0.638298 (-5119 2564);
PAINT MONO (-5119 2564);
FORCEPROP 2 LAST $XR16 82 
J 0
(-5209 2564);
DISPLAY 0.638298 (-5209 2564);
PAINT MONO (-5209 2564);
FORCEPROP 2 LAST $XR17 83 
J 0
(-5299 2564);
DISPLAY 0.638298 (-5299 2564);
PAINT MONO (-5299 2564);
FORCEPROP 2 LAST $XR18 84 
J 0
(-4579 2636);
DISPLAY 0.638298 (-4579 2636);
PAINT MONO (-4579 2636);
FORCEPROP 2 LAST $XR19 85 
J 0
(-4669 2636);
DISPLAY 0.638298 (-4669 2636);
PAINT MONO (-4669 2636);
FORCEPROP 2 LAST $XR20 86 
J 0
(-4759 2636);
DISPLAY 0.638298 (-4759 2636);
PAINT MONO (-4759 2636);
FORCEPROP 2 LAST $XR21 87 
J 0
(-4849 2636);
DISPLAY 0.638298 (-4849 2636);
PAINT MONO (-4849 2636);
FORCEPROP 2 LAST $XR22 88 
J 0
(-4939 2636);
DISPLAY 0.638298 (-4939 2636);
PAINT MONO (-4939 2636);
FORCEPROP 2 LAST $XR23 94 
J 0
(-5029 2636);
DISPLAY 0.638298 (-5029 2636);
PAINT MONO (-5029 2636);
FORCEPROP 2 LAST CDS_LIB mstr_standard
J 0
(-4325 2600);
DISPLAY 0.787234 (-4325 2600);
PAINT MONO (-4325 2600);
DISPLAY INVISIBLE (-4325 2600);
FORCEPROP 1 LAST OFFPAGE TRUE
J 0
(-4000 2475);
DISPLAY 1.404255 (-4000 2475);
PAINT GREEN (-4000 2475);
DISPLAY INVISIBLE (-4000 2475);
FORCEPROP 1 LAST COMMENT_BODY TRUE
J 0
(-4225 2525);
DISPLAY 1.404255 (-4225 2525);
PAINT GREEN (-4225 2525);
DISPLAY INVISIBLE (-4225 2525);
FORCEPROP 2 LAST PATH I176
J 0
(-4275 2675);
DISPLAY 0.787234 (-4275 2675);
PAINT ORANGE (-4275 2675);
DISPLAY INVISIBLE (-4275 2675);
FORCEADD GND..1
(-4600 1300);
FORCEPROP 3 LASTPIN (-4600 1350) SIG_NAME GND\g
J 0
(-4590 1360);
DISPLAY 0.659574 (-4590 1360);
PAINT MONO (-4590 1360);
DISPLAY INVISIBLE (-4590 1360);
FORCEPROP 1 LAST VOLTAGE 0
J 0
(-4600 1300);
PAINT SKYBLUE (-4600 1300);
DISPLAY INVISIBLE (-4600 1300);
FORCEPROP 2 LAST BOM_COST MEM
J 0
(-4600 1305);
PAINT ORANGE (-4600 1305);
DISPLAY INVISIBLE (-4600 1305);
FORCEPROP 1 LAST SIZE 1B
J 0
(-4525 1250);
DISPLAY 1.787234 (-4525 1250);
PAINT GREEN (-4525 1250);
DISPLAY INVISIBLE (-4525 1250);
FORCEPROP 2 LAST CDS_LIB mstr_symbols
J 0
(-4600 1300);
PAINT ORANGE (-4600 1300);
DISPLAY INVISIBLE (-4600 1300);
FORCEPROP 1 LAST BODY_TYPE PLUMBING
J 0
(-4645 1257);
DISPLAY 0.340426 (-4645 1257);
PAINT GREEN (-4645 1257);
DISPLAY INVISIBLE (-4645 1257);
FORCEPROP 1 LAST PATH I177
J 0
(-4525 1300);
DISPLAY 1.404255 (-4525 1300);
PAINT GREEN (-4525 1300);
DISPLAY INVISIBLE (-4525 1300);
FORCEPROP 2 LAST ROOM DDR4_CH_H
J 0
(-4600 1305);
PAINT ORANGE (-4600 1305);
DISPLAY INVISIBLE (-4600 1305);
FORCEPROP 1 LAST HDL_POWER GND
J 0
(-4600 1450);
DISPLAY 1.404255 (-4600 1450);
PAINT GREEN (-4600 1450);
DISPLAY INVISIBLE (-4600 1450);
FORCEADD CAP_A..1
R 2
(-4600 1550);
FORCEPROP 1 LAST LOCATION C9U7
J 2
(-4650 1650);
DISPLAY 0.617021 (-4650 1650);
PAINT AQUA (-4650 1650);
FORCEPROP 1 LAST PART_NUMBER A36096-045
J 2
(-4650 1400);
DISPLAY 0.617021 (-4650 1400);
PAINT BLUE (-4650 1400);
FORCEPROP 1 LAST VALUE 0.01UF
J 2
(-4650 1600);
DISPLAY 0.617021 (-4650 1600);
PAINT SKYBLUE (-4650 1600);
FORCEPROP 1 LAST TOLERANCE 10%
J 2
(-4650 1500);
DISPLAY 0.617021 (-4650 1500);
PAINT SKYBLUE (-4650 1500);
FORCEPROP 1 LAST PACK_TYPE 0402V
J 2
(-4650 1350);
DISPLAY 0.617021 (-4650 1350);
PAINT SKYBLUE (-4650 1350);
FORCEPROP 1 LAST VOLTAGE 25V
J 2
(-4650 1550);
DISPLAY 0.617021 (-4650 1550);
PAINT SKYBLUE (-4650 1550);
FORCEPROP 1 LAST MATERIAL X7R
J 2
(-4650 1450);
DISPLAY 0.617021 (-4650 1450);
PAINT SKYBLUE (-4650 1450);
FORCEPROP 2 LAST CDS_LOCATION C9U7
J 2
(-4650 1650);
DISPLAY 0.617021 (-4650 1650);
PAINT AQUA (-4650 1650);
DISPLAY INVISIBLE (-4650 1650);
FORCEPROP 2 LAST BOM_COST MEM
J 0
(-4600 1550);
PAINT ORANGE (-4600 1550);
DISPLAY INVISIBLE (-4600 1550);
FORCEPROP 2 LAST CDS_LIB dev_discrete
J 0
(-4600 1550);
PAINT ORANGE (-4600 1550);
DISPLAY INVISIBLE (-4600 1550);
FORCEPROP 2 LAST CDS_SEC 1
J 2
(-4650 1750);
PAINT MONO (-4650 1750);
DISPLAY INVISIBLE (-4650 1750);
FORCEPROP 2 LAST $SEC 1
J 0
(-4650 1750);
PAINT MONO (-4650 1750);
DISPLAY INVISIBLE (-4650 1750);
FORCEPROP 1 LAST PATH I178
J 2
(-4650 1700);
DISPLAY 0.978723 (-4650 1700);
PAINT WHITE (-4650 1700);
DISPLAY INVISIBLE (-4650 1700);
FORCEPROP 2 LAST ROOM DDR4_CH_J
J 0
(-4600 1550);
PAINT ORANGE (-4600 1550);
DISPLAY INVISIBLE (-4600 1550);
FORCEPROP 1 LASTPIN (-4600 1650) $PN 1
J 2
(-4610 1630);
DISPLAY 0.787234 (-4610 1630);
PAINT ORANGE (-4610 1630);
DISPLAY INVISIBLE (-4610 1630);
FORCEPROP 1 LASTPIN (-4600 1450) $PN 2
J 2
(-4610 1430);
DISPLAY 0.787234 (-4610 1430);
PAINT ORANGE (-4610 1430);
DISPLAY INVISIBLE (-4610 1430);
FORCEADD PVPP_GHJ..1
(-1150 3000);
FORCEPROP 3 LASTPIN (-1150 2950) SIG_NAME PVPP_GHJ\g
J 0
(-1140 2960);
DISPLAY 0.659574 (-1140 2960);
PAINT MONO (-1140 2960);
DISPLAY INVISIBLE (-1140 2960);
FORCEPROP 1 LAST VOLTAGE 2.5V
J 0
(-1195 2957);
DISPLAY 0.340426 (-1195 2957);
PAINT SKYBLUE (-1195 2957);
DISPLAY INVISIBLE (-1195 2957);
FORCEPROP 0 LAST BOM_COST MEM
J 0
(-1150 3100);
PAINT ORANGE (-1150 3100);
DISPLAY INVISIBLE (-1150 3100);
FORCEPROP 2 LAST CDS_LIB mstr_symbols
J 0
(-1150 3000);
PAINT ORANGE (-1150 3000);
DISPLAY INVISIBLE (-1150 3000);
FORCEPROP 1 LAST BODY_TYPE PLUMBING
J 0
(-1195 2957);
DISPLAY 0.340426 (-1195 2957);
PAINT GREEN (-1195 2957);
DISPLAY INVISIBLE (-1195 2957);
FORCEPROP 1 LAST PATH I179
J 0
(-1100 3025);
DISPLAY 0.872340 (-1100 3025);
PAINT AQUA (-1100 3025);
DISPLAY INVISIBLE (-1100 3025);
FORCEPROP 2 LAST ROOM DDR4_CH_H
J 0
(-1150 3100);
PAINT ORANGE (-1150 3100);
DISPLAY INVISIBLE (-1150 3100);
FORCEPROP 1 LAST HDL_POWER PVPP_GHJ
J 1
(-1150 3050);
DISPLAY 0.872340 (-1150 3050);
PAINT GREEN (-1150 3050);
DISPLAY INVISIBLE (-1150 3050);
FORCEADD TAP..6
R 2
(850 4500);
FORCEPROP 3 LASTPIN (800 4500) SIG_NAME M_H_DQS_DN<11>
J 0
(810 4510);
DISPLAY 0.659574 (810 4510);
PAINT MONO (810 4510);
DISPLAY INVISIBLE (810 4510);
FORCEPROP 1 LASTPIN (800 4500) BN 11
J 2
(850 4510);
DISPLAY 0.617021 (850 4510);
PAINT PINK (850 4510);
FORCEPROP 2 LAST CDS_LIB mstr_standard
J 0
(850 4500);
DISPLAY 0.787234 (850 4500);
PAINT MONO (850 4500);
DISPLAY INVISIBLE (850 4500);
FORCEPROP 1 LAST BODY_TYPE PLUMBING
J 2
(850 4450);
DISPLAY 1.234043 (850 4450);
PAINT GREEN (850 4450);
DISPLAY INVISIBLE (850 4450);
FORCEPROP 1 LAST HDL_TAP TRUE
J 2
(525 4375);
DISPLAY 1.234043 (525 4375);
PAINT GREEN (525 4375);
DISPLAY INVISIBLE (525 4375);
FORCEPROP 1 LAST PATH I18
J 2
(850 4500);
DISPLAY 0.936170 (850 4500);
PAINT GREEN (850 4500);
DISPLAY INVISIBLE (850 4500);
FORCEADD PVPP_GHJ..1
(-5200 2250);
FORCEPROP 3 LASTPIN (-5200 2200) SIG_NAME PVPP_GHJ\g
J 0
(-5190 2210);
DISPLAY 0.659574 (-5190 2210);
PAINT MONO (-5190 2210);
DISPLAY INVISIBLE (-5190 2210);
FORCEPROP 1 LAST VOLTAGE 2.5V
J 0
(-5245 2207);
DISPLAY 0.340426 (-5245 2207);
PAINT SKYBLUE (-5245 2207);
DISPLAY INVISIBLE (-5245 2207);
FORCEPROP 0 LAST BOM_COST MEM
J 0
(-5200 2350);
PAINT ORANGE (-5200 2350);
DISPLAY INVISIBLE (-5200 2350);
FORCEPROP 2 LAST CDS_LIB mstr_symbols
J 0
(-5200 2250);
PAINT ORANGE (-5200 2250);
DISPLAY INVISIBLE (-5200 2250);
FORCEPROP 1 LAST BODY_TYPE PLUMBING
J 0
(-5245 2207);
DISPLAY 0.340426 (-5245 2207);
PAINT GREEN (-5245 2207);
DISPLAY INVISIBLE (-5245 2207);
FORCEPROP 1 LAST PATH I180
J 0
(-5150 2275);
DISPLAY 0.872340 (-5150 2275);
PAINT AQUA (-5150 2275);
DISPLAY INVISIBLE (-5150 2275);
FORCEPROP 2 LAST ROOM DDR4_CH_H
J 0
(-5200 2350);
PAINT ORANGE (-5200 2350);
DISPLAY INVISIBLE (-5200 2350);
FORCEPROP 1 LAST HDL_POWER PVPP_GHJ
J 1
(-5200 2300);
DISPLAY 0.872340 (-5200 2300);
PAINT GREEN (-5200 2300);
DISPLAY INVISIBLE (-5200 2300);
FORCEADD OFFPAGE..1
(-4000 1450);
FORCEPROP 2 LAST $XR0 89 
J 0
(-4251 1450);
DISPLAY 0.638298 (-4251 1450);
PAINT MONO (-4251 1450);
FORCEPROP 2 LAST $XR1 77 
J 0
(-4341 1450);
DISPLAY 0.638298 (-4341 1450);
PAINT MONO (-4341 1450);
FORCEPROP 2 LAST $XR2 78 
J 0
(-4431 1450);
DISPLAY 0.638298 (-4431 1450);
PAINT MONO (-4431 1450);
FORCEPROP 2 LAST $XR3 80 
J 0
(-4521 1450);
DISPLAY 0.638298 (-4521 1450);
PAINT MONO (-4521 1450);
FORCEPROP 2 LAST $XR4 81 
J 0
(-4251 1414);
DISPLAY 0.638298 (-4251 1414);
PAINT MONO (-4251 1414);
FORCEPROP 2 LAST $XR5 82 
J 0
(-4341 1414);
DISPLAY 0.638298 (-4341 1414);
PAINT MONO (-4341 1414);
FORCEPROP 2 LAST CDS_LIB mstr_standard
J 0
(-4000 1450);
PAINT ORANGE (-4000 1450);
DISPLAY INVISIBLE (-4000 1450);
FORCEPROP 1 LAST OFFPAGE TRUE
J 0
(-3675 1325);
DISPLAY 0.936170 (-3675 1325);
PAINT GREEN (-3675 1325);
DISPLAY INVISIBLE (-3675 1325);
FORCEPROP 1 LAST COMMENT_BODY TRUE
J 0
(-3875 1350);
DISPLAY 0.936170 (-3875 1350);
PAINT GREEN (-3875 1350);
DISPLAY INVISIBLE (-3875 1350);
FORCEPROP 2 LAST PATH I181
J 0
(-3950 1525);
PAINT ORANGE (-3950 1525);
DISPLAY INVISIBLE (-3950 1525);
FORCEADD TAP..6
R 2
(650 3450);
FORCEPROP 3 LASTPIN (600 3450) SIG_NAME M_H_DQS_DP<0>
J 0
(610 3460);
DISPLAY 0.659574 (610 3460);
PAINT MONO (610 3460);
DISPLAY INVISIBLE (610 3460);
FORCEPROP 1 LASTPIN (600 3450) BN 0
J 2
(650 3460);
DISPLAY 0.617021 (650 3460);
PAINT PINK (650 3460);
FORCEPROP 2 LAST CDS_LIB mstr_standard
J 0
(650 3450);
DISPLAY 0.787234 (650 3450);
PAINT MONO (650 3450);
DISPLAY INVISIBLE (650 3450);
FORCEPROP 1 LAST BODY_TYPE PLUMBING
J 2
(650 3400);
DISPLAY 1.234043 (650 3400);
PAINT GREEN (650 3400);
DISPLAY INVISIBLE (650 3400);
FORCEPROP 1 LAST HDL_TAP TRUE
J 2
(325 3325);
DISPLAY 1.234043 (325 3325);
PAINT GREEN (325 3325);
DISPLAY INVISIBLE (325 3325);
FORCEPROP 1 LAST PATH I185
J 2
(652 3450);
DISPLAY 0.872340 (652 3450);
PAINT GREEN (652 3450);
DISPLAY INVISIBLE (652 3450);
FORCEADD P12V_NVDIMM_GHJ..1
(250 2975);
FORCEPROP 3 LASTPIN (250 2925) SIG_NAME P12V_NVDIMM_GHJ\g
J 0
(260 2935);
DISPLAY 0.659574 (260 2935);
PAINT MONO (260 2935);
DISPLAY INVISIBLE (260 2935);
FORCEPROP 1 LAST VOLTAGE 12.0
J 0
(205 2932);
DISPLAY 0.340426 (205 2932);
PAINT SKYBLUE (205 2932);
DISPLAY INVISIBLE (205 2932);
FORCEPROP 2 LAST CDS_LIB mstr_symbols
J 0
(250 2975);
PAINT ORANGE (250 2975);
DISPLAY INVISIBLE (250 2975);
FORCEPROP 1 LAST BODY_TYPE PLUMBING
J 0
(205 2932);
DISPLAY 0.340426 (205 2932);
PAINT GREEN (205 2932);
DISPLAY INVISIBLE (205 2932);
FORCEPROP 1 LAST PATH I186
J 0
(300 3000);
DISPLAY 0.872340 (300 3000);
PAINT AQUA (300 3000);
DISPLAY INVISIBLE (300 3000);
FORCEPROP 1 LAST HDL_POWER P12V_NVDIMM_GHJ
J 1
(250 3025);
DISPLAY 0.872340 (250 3025);
PAINT GREEN (250 3025);
DISPLAY INVISIBLE (250 3025);
FORCEADD TAP..6
R 2
(850 4400);
FORCEPROP 3 LASTPIN (800 4400) SIG_NAME M_H_DQS_DN<10>
J 0
(810 4410);
DISPLAY 0.659574 (810 4410);
PAINT MONO (810 4410);
DISPLAY INVISIBLE (810 4410);
FORCEPROP 1 LASTPIN (800 4400) BN 10
J 2
(850 4410);
DISPLAY 0.617021 (850 4410);
PAINT PINK (850 4410);
FORCEPROP 2 LAST CDS_LIB mstr_standard
J 0
(850 4400);
DISPLAY 0.787234 (850 4400);
PAINT MONO (850 4400);
DISPLAY INVISIBLE (850 4400);
FORCEPROP 1 LAST BODY_TYPE PLUMBING
J 2
(850 4350);
DISPLAY 1.234043 (850 4350);
PAINT GREEN (850 4350);
DISPLAY INVISIBLE (850 4350);
FORCEPROP 1 LAST HDL_TAP TRUE
J 2
(525 4275);
DISPLAY 1.234043 (525 4275);
PAINT GREEN (525 4275);
DISPLAY INVISIBLE (525 4275);
FORCEPROP 1 LAST PATH I19
J 2
(850 4400);
DISPLAY 0.936170 (850 4400);
PAINT GREEN (850 4400);
DISPLAY INVISIBLE (850 4400);
FORCEADD OFFPAGE..3
(1550 5200);
FORCEPROP 2 LAST $XR0 58 
J 0
(1764 5200);
DISPLAY 0.638298 (1764 5200);
PAINT MONO (1764 5200);
FORCEPROP 2 LAST $XR1 80 
J 0
(1854 5200);
DISPLAY 0.638298 (1854 5200);
PAINT MONO (1854 5200);
FORCEPROP 2 LAST CDS_LIB mstr_standard
J 0
(1550 5200);
DISPLAY 0.787234 (1550 5200);
PAINT MONO (1550 5200);
DISPLAY INVISIBLE (1550 5200);
FORCEPROP 1 LAST OFFPAGE TRUE
J 0
(1875 5075);
DISPLAY 0.936170 (1875 5075);
PAINT GREEN (1875 5075);
DISPLAY INVISIBLE (1875 5075);
FORCEPROP 1 LAST COMMENT_BODY TRUE
J 0
(1500 5100);
DISPLAY 0.936170 (1500 5100);
PAINT GREEN (1500 5100);
DISPLAY INVISIBLE (1500 5100);
FORCEPROP 2 LAST PATH I2
J 0
(1750 5275);
DISPLAY 0.787234 (1750 5275);
PAINT MONO (1750 5275);
DISPLAY INVISIBLE (1750 5275);
FORCEADD TAP..6
R 2
(850 4200);
FORCEPROP 3 LASTPIN (800 4200) SIG_NAME M_H_DQS_DN<8>
J 0
(810 4210);
DISPLAY 0.659574 (810 4210);
PAINT MONO (810 4210);
DISPLAY INVISIBLE (810 4210);
FORCEPROP 1 LASTPIN (800 4200) BN 8
J 2
(850 4210);
DISPLAY 0.617021 (850 4210);
PAINT PINK (850 4210);
FORCEPROP 2 LAST CDS_LIB mstr_standard
J 0
(850 4200);
DISPLAY 0.787234 (850 4200);
PAINT MONO (850 4200);
DISPLAY INVISIBLE (850 4200);
FORCEPROP 1 LAST BODY_TYPE PLUMBING
J 2
(850 4150);
DISPLAY 1.234043 (850 4150);
PAINT GREEN (850 4150);
DISPLAY INVISIBLE (850 4150);
FORCEPROP 1 LAST HDL_TAP TRUE
J 2
(525 4075);
DISPLAY 1.234043 (525 4075);
PAINT GREEN (525 4075);
DISPLAY INVISIBLE (525 4075);
FORCEPROP 1 LAST PATH I20
J 2
(850 4200);
DISPLAY 0.936170 (850 4200);
PAINT GREEN (850 4200);
DISPLAY INVISIBLE (850 4200);
FORCEADD TAP..6
R 2
(850 4300);
FORCEPROP 3 LASTPIN (800 4300) SIG_NAME M_H_DQS_DN<9>
J 0
(810 4310);
DISPLAY 0.659574 (810 4310);
PAINT MONO (810 4310);
DISPLAY INVISIBLE (810 4310);
FORCEPROP 1 LASTPIN (800 4300) BN 9
J 2
(850 4310);
DISPLAY 0.617021 (850 4310);
PAINT PINK (850 4310);
FORCEPROP 2 LAST CDS_LIB mstr_standard
J 0
(850 4300);
DISPLAY 0.787234 (850 4300);
PAINT MONO (850 4300);
DISPLAY INVISIBLE (850 4300);
FORCEPROP 1 LAST BODY_TYPE PLUMBING
J 2
(850 4250);
DISPLAY 1.234043 (850 4250);
PAINT GREEN (850 4250);
DISPLAY INVISIBLE (850 4250);
FORCEPROP 1 LAST HDL_TAP TRUE
J 2
(525 4175);
DISPLAY 1.234043 (525 4175);
PAINT GREEN (525 4175);
DISPLAY INVISIBLE (525 4175);
FORCEPROP 1 LAST PATH I21
J 2
(850 4300);
DISPLAY 0.936170 (850 4300);
PAINT GREEN (850 4300);
DISPLAY INVISIBLE (850 4300);
FORCEADD TAP..6
R 2
(650 4550);
FORCEPROP 3 LASTPIN (600 4550) SIG_NAME M_H_DQS_DP<11>
J 0
(610 4560);
DISPLAY 0.659574 (610 4560);
PAINT MONO (610 4560);
DISPLAY INVISIBLE (610 4560);
FORCEPROP 1 LASTPIN (600 4550) BN 11
J 2
(650 4560);
DISPLAY 0.617021 (650 4560);
PAINT PINK (650 4560);
FORCEPROP 2 LAST CDS_LIB mstr_standard
J 0
(650 4550);
DISPLAY 0.787234 (650 4550);
PAINT MONO (650 4550);
DISPLAY INVISIBLE (650 4550);
FORCEPROP 1 LAST BODY_TYPE PLUMBING
J 2
(650 4500);
DISPLAY 1.234043 (650 4500);
PAINT GREEN (650 4500);
DISPLAY INVISIBLE (650 4500);
FORCEPROP 1 LAST HDL_TAP TRUE
J 2
(325 4425);
DISPLAY 1.234043 (325 4425);
PAINT GREEN (325 4425);
DISPLAY INVISIBLE (325 4425);
FORCEPROP 1 LAST PATH I22
J 2
(650 4550);
DISPLAY 0.936170 (650 4550);
PAINT GREEN (650 4550);
DISPLAY INVISIBLE (650 4550);
FORCEADD TAP..6
R 2
(650 4450);
FORCEPROP 3 LASTPIN (600 4450) SIG_NAME M_H_DQS_DP<10>
J 0
(610 4460);
DISPLAY 0.659574 (610 4460);
PAINT MONO (610 4460);
DISPLAY INVISIBLE (610 4460);
FORCEPROP 1 LASTPIN (600 4450) BN 10
J 2
(650 4460);
DISPLAY 0.617021 (650 4460);
PAINT PINK (650 4460);
FORCEPROP 2 LAST CDS_LIB mstr_standard
J 0
(650 4450);
DISPLAY 0.787234 (650 4450);
PAINT MONO (650 4450);
DISPLAY INVISIBLE (650 4450);
FORCEPROP 1 LAST BODY_TYPE PLUMBING
J 2
(650 4400);
DISPLAY 1.234043 (650 4400);
PAINT GREEN (650 4400);
DISPLAY INVISIBLE (650 4400);
FORCEPROP 1 LAST HDL_TAP TRUE
J 2
(325 4325);
DISPLAY 1.234043 (325 4325);
PAINT GREEN (325 4325);
DISPLAY INVISIBLE (325 4325);
FORCEPROP 1 LAST PATH I23
J 2
(650 4450);
DISPLAY 0.936170 (650 4450);
PAINT GREEN (650 4450);
DISPLAY INVISIBLE (650 4450);
FORCEADD TAP..6
R 2
(650 4350);
FORCEPROP 3 LASTPIN (600 4350) SIG_NAME M_H_DQS_DP<9>
J 0
(610 4360);
DISPLAY 0.659574 (610 4360);
PAINT MONO (610 4360);
DISPLAY INVISIBLE (610 4360);
FORCEPROP 1 LASTPIN (600 4350) BN 9
J 2
(650 4360);
DISPLAY 0.617021 (650 4360);
PAINT PINK (650 4360);
FORCEPROP 2 LAST CDS_LIB mstr_standard
J 0
(650 4350);
DISPLAY 0.787234 (650 4350);
PAINT MONO (650 4350);
DISPLAY INVISIBLE (650 4350);
FORCEPROP 1 LAST BODY_TYPE PLUMBING
J 2
(650 4300);
DISPLAY 1.234043 (650 4300);
PAINT GREEN (650 4300);
DISPLAY INVISIBLE (650 4300);
FORCEPROP 1 LAST HDL_TAP TRUE
J 2
(325 4225);
DISPLAY 1.234043 (325 4225);
PAINT GREEN (325 4225);
DISPLAY INVISIBLE (325 4225);
FORCEPROP 1 LAST PATH I24
J 2
(650 4350);
DISPLAY 0.936170 (650 4350);
PAINT GREEN (650 4350);
DISPLAY INVISIBLE (650 4350);
FORCEADD TAP..6
R 2
(650 4250);
FORCEPROP 3 LASTPIN (600 4250) SIG_NAME M_H_DQS_DP<8>
J 0
(610 4260);
DISPLAY 0.659574 (610 4260);
PAINT MONO (610 4260);
DISPLAY INVISIBLE (610 4260);
FORCEPROP 1 LASTPIN (600 4250) BN 8
J 2
(650 4260);
DISPLAY 0.617021 (650 4260);
PAINT PINK (650 4260);
FORCEPROP 2 LAST CDS_LIB mstr_standard
J 0
(650 4250);
DISPLAY 0.787234 (650 4250);
PAINT MONO (650 4250);
DISPLAY INVISIBLE (650 4250);
FORCEPROP 1 LAST BODY_TYPE PLUMBING
J 2
(650 4200);
DISPLAY 1.234043 (650 4200);
PAINT GREEN (650 4200);
DISPLAY INVISIBLE (650 4200);
FORCEPROP 1 LAST HDL_TAP TRUE
J 2
(325 4125);
DISPLAY 1.234043 (325 4125);
PAINT GREEN (325 4125);
DISPLAY INVISIBLE (325 4125);
FORCEPROP 1 LAST PATH I25
J 2
(650 4250);
DISPLAY 0.936170 (650 4250);
PAINT GREEN (650 4250);
DISPLAY INVISIBLE (650 4250);
FORCEADD TAP..6
R 2
(650 4150);
FORCEPROP 3 LASTPIN (600 4150) SIG_NAME M_H_DQS_DP<7>
J 0
(610 4160);
DISPLAY 0.659574 (610 4160);
PAINT MONO (610 4160);
DISPLAY INVISIBLE (610 4160);
FORCEPROP 1 LASTPIN (600 4150) BN 7
J 2
(650 4160);
DISPLAY 0.617021 (650 4160);
PAINT PINK (650 4160);
FORCEPROP 2 LAST CDS_LIB mstr_standard
J 0
(650 4150);
DISPLAY 0.787234 (650 4150);
PAINT MONO (650 4150);
DISPLAY INVISIBLE (650 4150);
FORCEPROP 1 LAST BODY_TYPE PLUMBING
J 2
(650 4100);
DISPLAY 1.234043 (650 4100);
PAINT GREEN (650 4100);
DISPLAY INVISIBLE (650 4100);
FORCEPROP 1 LAST HDL_TAP TRUE
J 2
(325 4025);
DISPLAY 1.234043 (325 4025);
PAINT GREEN (325 4025);
DISPLAY INVISIBLE (325 4025);
FORCEPROP 1 LAST PATH I26
J 2
(650 4150);
DISPLAY 0.936170 (650 4150);
PAINT GREEN (650 4150);
DISPLAY INVISIBLE (650 4150);
FORCEADD TAP..6
R 2
(850 4100);
FORCEPROP 3 LASTPIN (800 4100) SIG_NAME M_H_DQS_DN<7>
J 0
(810 4110);
DISPLAY 0.659574 (810 4110);
PAINT MONO (810 4110);
DISPLAY INVISIBLE (810 4110);
FORCEPROP 1 LASTPIN (800 4100) BN 7
J 2
(850 4110);
DISPLAY 0.617021 (850 4110);
PAINT PINK (850 4110);
FORCEPROP 2 LAST CDS_LIB mstr_standard
J 0
(850 4100);
DISPLAY 0.787234 (850 4100);
PAINT MONO (850 4100);
DISPLAY INVISIBLE (850 4100);
FORCEPROP 1 LAST BODY_TYPE PLUMBING
J 2
(850 4050);
DISPLAY 1.234043 (850 4050);
PAINT GREEN (850 4050);
DISPLAY INVISIBLE (850 4050);
FORCEPROP 1 LAST HDL_TAP TRUE
J 2
(525 3975);
DISPLAY 1.234043 (525 3975);
PAINT GREEN (525 3975);
DISPLAY INVISIBLE (525 3975);
FORCEPROP 1 LAST PATH I27
J 2
(850 4100);
DISPLAY 0.936170 (850 4100);
PAINT GREEN (850 4100);
DISPLAY INVISIBLE (850 4100);
FORCEADD TAP..6
R 2
(850 4000);
FORCEPROP 3 LASTPIN (800 4000) SIG_NAME M_H_DQS_DN<6>
J 0
(810 4010);
DISPLAY 0.659574 (810 4010);
PAINT MONO (810 4010);
DISPLAY INVISIBLE (810 4010);
FORCEPROP 1 LASTPIN (800 4000) BN 6
J 2
(850 4010);
DISPLAY 0.617021 (850 4010);
PAINT PINK (850 4010);
FORCEPROP 2 LAST CDS_LIB mstr_standard
J 0
(850 4000);
DISPLAY 0.787234 (850 4000);
PAINT MONO (850 4000);
DISPLAY INVISIBLE (850 4000);
FORCEPROP 1 LAST BODY_TYPE PLUMBING
J 2
(850 3950);
DISPLAY 1.234043 (850 3950);
PAINT GREEN (850 3950);
DISPLAY INVISIBLE (850 3950);
FORCEPROP 1 LAST HDL_TAP TRUE
J 2
(525 3875);
DISPLAY 1.234043 (525 3875);
PAINT GREEN (525 3875);
DISPLAY INVISIBLE (525 3875);
FORCEPROP 1 LAST PATH I28
J 2
(850 4000);
DISPLAY 0.936170 (850 4000);
PAINT GREEN (850 4000);
DISPLAY INVISIBLE (850 4000);
FORCEADD TAP..6
R 2
(850 3900);
FORCEPROP 3 LASTPIN (800 3900) SIG_NAME M_H_DQS_DN<5>
J 0
(810 3910);
DISPLAY 0.659574 (810 3910);
PAINT MONO (810 3910);
DISPLAY INVISIBLE (810 3910);
FORCEPROP 1 LASTPIN (800 3900) BN 5
J 2
(850 3910);
DISPLAY 0.617021 (850 3910);
PAINT PINK (850 3910);
FORCEPROP 2 LAST CDS_LIB mstr_standard
J 0
(850 3900);
DISPLAY 0.787234 (850 3900);
PAINT MONO (850 3900);
DISPLAY INVISIBLE (850 3900);
FORCEPROP 1 LAST BODY_TYPE PLUMBING
J 2
(850 3850);
DISPLAY 1.234043 (850 3850);
PAINT GREEN (850 3850);
DISPLAY INVISIBLE (850 3850);
FORCEPROP 1 LAST HDL_TAP TRUE
J 2
(525 3775);
DISPLAY 1.234043 (525 3775);
PAINT GREEN (525 3775);
DISPLAY INVISIBLE (525 3775);
FORCEPROP 1 LAST PATH I29
J 2
(850 3900);
DISPLAY 0.936170 (850 3900);
PAINT GREEN (850 3900);
DISPLAY INVISIBLE (850 3900);
FORCEADD TAP..6
R 2
(850 5100);
FORCEPROP 3 LASTPIN (800 5100) SIG_NAME M_H_DQS_DN<17>
J 0
(810 5110);
DISPLAY 0.659574 (810 5110);
PAINT MONO (810 5110);
DISPLAY INVISIBLE (810 5110);
FORCEPROP 1 LASTPIN (800 5100) BN 17
J 2
(850 5110);
DISPLAY 0.617021 (850 5110);
PAINT PINK (850 5110);
FORCEPROP 2 LAST CDS_LIB mstr_standard
J 2
(850 5100);
DISPLAY 0.787234 (850 5100);
PAINT MONO (850 5100);
DISPLAY INVISIBLE (850 5100);
FORCEPROP 1 LAST BODY_TYPE PLUMBING
J 2
(850 5050);
DISPLAY 1.234043 (850 5050);
PAINT GREEN (850 5050);
DISPLAY INVISIBLE (850 5050);
FORCEPROP 1 LAST HDL_TAP TRUE
J 2
(525 4975);
DISPLAY 1.234043 (525 4975);
PAINT GREEN (525 4975);
DISPLAY INVISIBLE (525 4975);
FORCEPROP 1 LAST PATH I3
J 2
(850 5100);
DISPLAY 0.936170 (850 5100);
PAINT GREEN (850 5100);
DISPLAY INVISIBLE (850 5100);
FORCEADD TAP..6
R 2
(850 3700);
FORCEPROP 3 LASTPIN (800 3700) SIG_NAME M_H_DQS_DN<3>
J 0
(810 3710);
DISPLAY 0.659574 (810 3710);
PAINT MONO (810 3710);
DISPLAY INVISIBLE (810 3710);
FORCEPROP 1 LASTPIN (800 3700) BN 3
J 2
(850 3710);
DISPLAY 0.617021 (850 3710);
PAINT PINK (850 3710);
FORCEPROP 2 LAST CDS_LIB mstr_standard
J 0
(850 3700);
DISPLAY 0.787234 (850 3700);
PAINT MONO (850 3700);
DISPLAY INVISIBLE (850 3700);
FORCEPROP 1 LAST BODY_TYPE PLUMBING
J 2
(850 3650);
DISPLAY 1.234043 (850 3650);
PAINT GREEN (850 3650);
DISPLAY INVISIBLE (850 3650);
FORCEPROP 1 LAST HDL_TAP TRUE
J 2
(525 3575);
DISPLAY 1.234043 (525 3575);
PAINT GREEN (525 3575);
DISPLAY INVISIBLE (525 3575);
FORCEPROP 1 LAST PATH I30
J 2
(850 3700);
DISPLAY 0.936170 (850 3700);
PAINT GREEN (850 3700);
DISPLAY INVISIBLE (850 3700);
FORCEADD TAP..6
R 2
(850 3800);
FORCEPROP 3 LASTPIN (800 3800) SIG_NAME M_H_DQS_DN<4>
J 0
(810 3810);
DISPLAY 0.659574 (810 3810);
PAINT MONO (810 3810);
DISPLAY INVISIBLE (810 3810);
FORCEPROP 1 LASTPIN (800 3800) BN 4
J 2
(850 3810);
DISPLAY 0.617021 (850 3810);
PAINT PINK (850 3810);
FORCEPROP 2 LAST CDS_LIB mstr_standard
J 0
(850 3800);
DISPLAY 0.787234 (850 3800);
PAINT MONO (850 3800);
DISPLAY INVISIBLE (850 3800);
FORCEPROP 1 LAST BODY_TYPE PLUMBING
J 2
(850 3750);
DISPLAY 1.234043 (850 3750);
PAINT GREEN (850 3750);
DISPLAY INVISIBLE (850 3750);
FORCEPROP 1 LAST HDL_TAP TRUE
J 2
(525 3675);
DISPLAY 1.234043 (525 3675);
PAINT GREEN (525 3675);
DISPLAY INVISIBLE (525 3675);
FORCEPROP 1 LAST PATH I31
J 2
(850 3800);
DISPLAY 0.936170 (850 3800);
PAINT GREEN (850 3800);
DISPLAY INVISIBLE (850 3800);
FORCEADD TAP..6
R 2
(650 4050);
FORCEPROP 3 LASTPIN (600 4050) SIG_NAME M_H_DQS_DP<6>
J 0
(610 4060);
DISPLAY 0.659574 (610 4060);
PAINT MONO (610 4060);
DISPLAY INVISIBLE (610 4060);
FORCEPROP 1 LASTPIN (600 4050) BN 6
J 2
(650 4060);
DISPLAY 0.617021 (650 4060);
PAINT PINK (650 4060);
FORCEPROP 2 LAST CDS_LIB mstr_standard
J 0
(650 4050);
DISPLAY 0.787234 (650 4050);
PAINT MONO (650 4050);
DISPLAY INVISIBLE (650 4050);
FORCEPROP 1 LAST BODY_TYPE PLUMBING
J 2
(650 4000);
DISPLAY 1.234043 (650 4000);
PAINT GREEN (650 4000);
DISPLAY INVISIBLE (650 4000);
FORCEPROP 1 LAST HDL_TAP TRUE
J 2
(325 3925);
DISPLAY 1.234043 (325 3925);
PAINT GREEN (325 3925);
DISPLAY INVISIBLE (325 3925);
FORCEPROP 1 LAST PATH I32
J 2
(650 4050);
DISPLAY 0.936170 (650 4050);
PAINT GREEN (650 4050);
DISPLAY INVISIBLE (650 4050);
FORCEADD TAP..6
R 2
(650 3950);
FORCEPROP 3 LASTPIN (600 3950) SIG_NAME M_H_DQS_DP<5>
J 0
(610 3960);
DISPLAY 0.659574 (610 3960);
PAINT MONO (610 3960);
DISPLAY INVISIBLE (610 3960);
FORCEPROP 1 LASTPIN (600 3950) BN 5
J 2
(650 3960);
DISPLAY 0.617021 (650 3960);
PAINT PINK (650 3960);
FORCEPROP 2 LAST CDS_LIB mstr_standard
J 0
(650 3950);
DISPLAY 0.787234 (650 3950);
PAINT MONO (650 3950);
DISPLAY INVISIBLE (650 3950);
FORCEPROP 1 LAST BODY_TYPE PLUMBING
J 2
(650 3900);
DISPLAY 1.234043 (650 3900);
PAINT GREEN (650 3900);
DISPLAY INVISIBLE (650 3900);
FORCEPROP 1 LAST HDL_TAP TRUE
J 2
(325 3825);
DISPLAY 1.234043 (325 3825);
PAINT GREEN (325 3825);
DISPLAY INVISIBLE (325 3825);
FORCEPROP 1 LAST PATH I33
J 2
(650 3950);
DISPLAY 0.936170 (650 3950);
PAINT GREEN (650 3950);
DISPLAY INVISIBLE (650 3950);
FORCEADD TAP..6
R 2
(650 3850);
FORCEPROP 3 LASTPIN (600 3850) SIG_NAME M_H_DQS_DP<4>
J 0
(610 3860);
DISPLAY 0.659574 (610 3860);
PAINT MONO (610 3860);
DISPLAY INVISIBLE (610 3860);
FORCEPROP 1 LASTPIN (600 3850) BN 4
J 2
(650 3860);
DISPLAY 0.617021 (650 3860);
PAINT PINK (650 3860);
FORCEPROP 2 LAST CDS_LIB mstr_standard
J 0
(650 3850);
DISPLAY 0.787234 (650 3850);
PAINT MONO (650 3850);
DISPLAY INVISIBLE (650 3850);
FORCEPROP 1 LAST BODY_TYPE PLUMBING
J 2
(650 3800);
DISPLAY 1.234043 (650 3800);
PAINT GREEN (650 3800);
DISPLAY INVISIBLE (650 3800);
FORCEPROP 1 LAST HDL_TAP TRUE
J 2
(325 3725);
DISPLAY 1.234043 (325 3725);
PAINT GREEN (325 3725);
DISPLAY INVISIBLE (325 3725);
FORCEPROP 1 LAST PATH I34
J 2
(650 3850);
DISPLAY 0.936170 (650 3850);
PAINT GREEN (650 3850);
DISPLAY INVISIBLE (650 3850);
FORCEADD TAP..6
R 2
(650 3750);
FORCEPROP 3 LASTPIN (600 3750) SIG_NAME M_H_DQS_DP<3>
J 0
(610 3760);
DISPLAY 0.659574 (610 3760);
PAINT MONO (610 3760);
DISPLAY INVISIBLE (610 3760);
FORCEPROP 1 LASTPIN (600 3750) BN 3
J 2
(650 3760);
DISPLAY 0.617021 (650 3760);
PAINT PINK (650 3760);
FORCEPROP 2 LAST CDS_LIB mstr_standard
J 0
(650 3750);
DISPLAY 0.787234 (650 3750);
PAINT MONO (650 3750);
DISPLAY INVISIBLE (650 3750);
FORCEPROP 1 LAST BODY_TYPE PLUMBING
J 2
(650 3700);
DISPLAY 1.234043 (650 3700);
PAINT GREEN (650 3700);
DISPLAY INVISIBLE (650 3700);
FORCEPROP 1 LAST HDL_TAP TRUE
J 2
(325 3625);
DISPLAY 1.234043 (325 3625);
PAINT GREEN (325 3625);
DISPLAY INVISIBLE (325 3625);
FORCEPROP 1 LAST PATH I35
J 2
(650 3750);
DISPLAY 0.936170 (650 3750);
PAINT GREEN (650 3750);
DISPLAY INVISIBLE (650 3750);
FORCEADD TAP..6
R 2
(650 3650);
FORCEPROP 3 LASTPIN (600 3650) SIG_NAME M_H_DQS_DP<2>
J 0
(610 3660);
DISPLAY 0.659574 (610 3660);
PAINT MONO (610 3660);
DISPLAY INVISIBLE (610 3660);
FORCEPROP 1 LASTPIN (600 3650) BN 2
J 2
(650 3660);
DISPLAY 0.617021 (650 3660);
PAINT PINK (650 3660);
FORCEPROP 2 LAST CDS_LIB mstr_standard
J 0
(650 3650);
DISPLAY 0.787234 (650 3650);
PAINT MONO (650 3650);
DISPLAY INVISIBLE (650 3650);
FORCEPROP 1 LAST BODY_TYPE PLUMBING
J 2
(650 3600);
DISPLAY 1.234043 (650 3600);
PAINT GREEN (650 3600);
DISPLAY INVISIBLE (650 3600);
FORCEPROP 1 LAST HDL_TAP TRUE
J 2
(325 3525);
DISPLAY 1.234043 (325 3525);
PAINT GREEN (325 3525);
DISPLAY INVISIBLE (325 3525);
FORCEPROP 1 LAST PATH I36
J 2
(650 3650);
DISPLAY 0.936170 (650 3650);
PAINT GREEN (650 3650);
DISPLAY INVISIBLE (650 3650);
FORCEADD TAP..6
R 2
(850 3500);
FORCEPROP 3 LASTPIN (800 3500) SIG_NAME M_H_DQS_DN<1>
J 0
(810 3510);
DISPLAY 0.659574 (810 3510);
PAINT MONO (810 3510);
DISPLAY INVISIBLE (810 3510);
FORCEPROP 1 LASTPIN (800 3500) BN 1
J 2
(850 3510);
DISPLAY 0.617021 (850 3510);
PAINT PINK (850 3510);
FORCEPROP 2 LAST CDS_LIB mstr_standard
J 0
(850 3500);
DISPLAY 0.787234 (850 3500);
PAINT MONO (850 3500);
DISPLAY INVISIBLE (850 3500);
FORCEPROP 1 LAST BODY_TYPE PLUMBING
J 2
(850 3450);
DISPLAY 1.234043 (850 3450);
PAINT GREEN (850 3450);
DISPLAY INVISIBLE (850 3450);
FORCEPROP 1 LAST HDL_TAP TRUE
J 2
(525 3375);
DISPLAY 1.234043 (525 3375);
PAINT GREEN (525 3375);
DISPLAY INVISIBLE (525 3375);
FORCEPROP 1 LAST PATH I37
J 2
(850 3500);
DISPLAY 0.936170 (850 3500);
PAINT GREEN (850 3500);
DISPLAY INVISIBLE (850 3500);
FORCEADD TAP..6
R 2
(850 3600);
FORCEPROP 3 LASTPIN (800 3600) SIG_NAME M_H_DQS_DN<2>
J 0
(810 3610);
DISPLAY 0.659574 (810 3610);
PAINT MONO (810 3610);
DISPLAY INVISIBLE (810 3610);
FORCEPROP 1 LASTPIN (800 3600) BN 2
J 2
(850 3610);
DISPLAY 0.617021 (850 3610);
PAINT PINK (850 3610);
FORCEPROP 2 LAST CDS_LIB mstr_standard
J 0
(850 3600);
DISPLAY 0.787234 (850 3600);
PAINT MONO (850 3600);
DISPLAY INVISIBLE (850 3600);
FORCEPROP 1 LAST BODY_TYPE PLUMBING
J 2
(850 3550);
DISPLAY 1.234043 (850 3550);
PAINT GREEN (850 3550);
DISPLAY INVISIBLE (850 3550);
FORCEPROP 1 LAST HDL_TAP TRUE
J 2
(525 3475);
DISPLAY 1.234043 (525 3475);
PAINT GREEN (525 3475);
DISPLAY INVISIBLE (525 3475);
FORCEPROP 1 LAST PATH I38
J 2
(850 3600);
DISPLAY 0.936170 (850 3600);
PAINT GREEN (850 3600);
DISPLAY INVISIBLE (850 3600);
FORCEADD TAP..6
R 2
(850 3400);
FORCEPROP 3 LASTPIN (800 3400) SIG_NAME M_H_DQS_DN<0>
J 0
(810 3410);
DISPLAY 0.659574 (810 3410);
PAINT MONO (810 3410);
DISPLAY INVISIBLE (810 3410);
FORCEPROP 1 LASTPIN (800 3400) BN 0
J 2
(850 3410);
DISPLAY 0.617021 (850 3410);
PAINT PINK (850 3410);
FORCEPROP 2 LAST CDS_LIB mstr_standard
J 0
(850 3400);
DISPLAY 0.787234 (850 3400);
PAINT MONO (850 3400);
DISPLAY INVISIBLE (850 3400);
FORCEPROP 1 LAST BODY_TYPE PLUMBING
J 2
(850 3350);
DISPLAY 1.234043 (850 3350);
PAINT GREEN (850 3350);
DISPLAY INVISIBLE (850 3350);
FORCEPROP 1 LAST HDL_TAP TRUE
J 2
(525 3275);
DISPLAY 1.234043 (525 3275);
PAINT GREEN (525 3275);
DISPLAY INVISIBLE (525 3275);
FORCEPROP 1 LAST PATH I39
J 2
(850 3400);
DISPLAY 0.936170 (850 3400);
PAINT GREEN (850 3400);
DISPLAY INVISIBLE (850 3400);
FORCEADD TAP..6
R 2
(850 5000);
FORCEPROP 3 LASTPIN (800 5000) SIG_NAME M_H_DQS_DN<16>
J 0
(810 5010);
DISPLAY 0.659574 (810 5010);
PAINT MONO (810 5010);
DISPLAY INVISIBLE (810 5010);
FORCEPROP 1 LASTPIN (800 5000) BN 16
J 2
(850 5010);
DISPLAY 0.617021 (850 5010);
PAINT PINK (850 5010);
FORCEPROP 2 LAST CDS_LIB mstr_standard
J 0
(850 5000);
DISPLAY 0.787234 (850 5000);
PAINT MONO (850 5000);
DISPLAY INVISIBLE (850 5000);
FORCEPROP 1 LAST BODY_TYPE PLUMBING
J 2
(850 4950);
DISPLAY 1.234043 (850 4950);
PAINT GREEN (850 4950);
DISPLAY INVISIBLE (850 4950);
FORCEPROP 1 LAST HDL_TAP TRUE
J 2
(525 4875);
DISPLAY 1.234043 (525 4875);
PAINT GREEN (525 4875);
DISPLAY INVISIBLE (525 4875);
FORCEPROP 1 LAST PATH I4
J 2
(850 5000);
DISPLAY 0.936170 (850 5000);
PAINT GREEN (850 5000);
DISPLAY INVISIBLE (850 5000);
FORCEADD TAP..6
R 2
(650 3550);
FORCEPROP 3 LASTPIN (600 3550) SIG_NAME M_H_DQS_DP<1>
J 0
(610 3560);
DISPLAY 0.659574 (610 3560);
PAINT MONO (610 3560);
DISPLAY INVISIBLE (610 3560);
FORCEPROP 1 LASTPIN (600 3550) BN 1
J 2
(650 3560);
DISPLAY 0.617021 (650 3560);
PAINT PINK (650 3560);
FORCEPROP 2 LAST CDS_LIB mstr_standard
J 0
(650 3550);
DISPLAY 0.787234 (650 3550);
PAINT MONO (650 3550);
DISPLAY INVISIBLE (650 3550);
FORCEPROP 1 LAST BODY_TYPE PLUMBING
J 2
(650 3500);
DISPLAY 1.234043 (650 3500);
PAINT GREEN (650 3500);
DISPLAY INVISIBLE (650 3500);
FORCEPROP 1 LAST HDL_TAP TRUE
J 2
(325 3425);
DISPLAY 1.234043 (325 3425);
PAINT GREEN (325 3425);
DISPLAY INVISIBLE (325 3425);
FORCEPROP 1 LAST PATH I40
J 2
(650 3550);
DISPLAY 0.936170 (650 3550);
PAINT GREEN (650 3550);
DISPLAY INVISIBLE (650 3550);
FORCEADD SCONN288_H44441004..3
(1750 2400);
FORCEPROP 1 LAST LOCATION J1G2
J 0
(1300 3800);
DISPLAY 0.617021 (1300 3800);
PAINT AQUA (1300 3800);
FORCEPROP 1 LAST PART_NUMBER H44441-004
J 0
(1300 1050);
DISPLAY 0.617021 (1300 1050);
PAINT BLUE (1300 1050);
FORCEPROP 1 LAST MATERIAL SCONN
J 0
(1300 3750);
DISPLAY 0.617021 (1300 3750);
PAINT SKYBLUE (1300 3750);
FORCEPROP 2 LASTPIN (1250 3550) $PN 2
J 2
(1240 3560);
DISPLAY 0.617021 (1240 3560);
PAINT ORANGE (1240 3560);
FORCEPROP 2 LASTPIN (1250 3500) $PN 4
J 2
(1240 3510);
DISPLAY 0.617021 (1240 3510);
PAINT ORANGE (1240 3510);
FORCEPROP 2 LASTPIN (1250 3450) $PN 6
J 2
(1240 3460);
DISPLAY 0.617021 (1240 3460);
PAINT ORANGE (1240 3460);
FORCEPROP 2 LASTPIN (1250 3400) $PN 9
J 2
(1240 3410);
DISPLAY 0.617021 (1240 3410);
PAINT ORANGE (1240 3410);
FORCEPROP 2 LASTPIN (1250 3350) $PN 11
J 2
(1240 3360);
DISPLAY 0.617021 (1240 3360);
PAINT ORANGE (1240 3360);
FORCEPROP 2 LASTPIN (1250 3300) $PN 13
J 2
(1240 3310);
DISPLAY 0.617021 (1240 3310);
PAINT ORANGE (1240 3310);
FORCEPROP 2 LASTPIN (1250 3250) $PN 15
J 2
(1240 3260);
DISPLAY 0.617021 (1240 3260);
PAINT ORANGE (1240 3260);
FORCEPROP 2 LASTPIN (1250 3200) $PN 17
J 2
(1240 3210);
DISPLAY 0.617021 (1240 3210);
PAINT ORANGE (1240 3210);
FORCEPROP 2 LASTPIN (1250 3150) $PN 20
J 2
(1240 3160);
DISPLAY 0.617021 (1240 3160);
PAINT ORANGE (1240 3160);
FORCEPROP 2 LASTPIN (1250 3100) $PN 22
J 2
(1240 3110);
DISPLAY 0.617021 (1240 3110);
PAINT ORANGE (1240 3110);
FORCEPROP 2 LASTPIN (1250 3050) $PN 24
J 2
(1240 3060);
DISPLAY 0.617021 (1240 3060);
PAINT ORANGE (1240 3060);
FORCEPROP 2 LASTPIN (1250 3000) $PN 26
J 2
(1240 3010);
DISPLAY 0.617021 (1240 3010);
PAINT ORANGE (1240 3010);
FORCEPROP 2 LASTPIN (1250 2950) $PN 28
J 2
(1240 2960);
DISPLAY 0.617021 (1240 2960);
PAINT ORANGE (1240 2960);
FORCEPROP 2 LASTPIN (1250 2900) $PN 31
J 2
(1240 2910);
DISPLAY 0.617021 (1240 2910);
PAINT ORANGE (1240 2910);
FORCEPROP 2 LASTPIN (1250 2850) $PN 33
J 2
(1240 2860);
DISPLAY 0.617021 (1240 2860);
PAINT ORANGE (1240 2860);
FORCEPROP 2 LASTPIN (1250 2800) $PN 35
J 2
(1240 2810);
DISPLAY 0.617021 (1240 2810);
PAINT ORANGE (1240 2810);
FORCEPROP 2 LASTPIN (1250 2750) $PN 37
J 2
(1240 2760);
DISPLAY 0.617021 (1240 2760);
PAINT ORANGE (1240 2760);
FORCEPROP 2 LASTPIN (1250 2700) $PN 39
J 2
(1240 2710);
DISPLAY 0.617021 (1240 2710);
PAINT ORANGE (1240 2710);
FORCEPROP 2 LASTPIN (1250 2650) $PN 42
J 2
(1240 2660);
DISPLAY 0.617021 (1240 2660);
PAINT ORANGE (1240 2660);
FORCEPROP 2 LASTPIN (1250 2600) $PN 44
J 2
(1240 2610);
DISPLAY 0.617021 (1240 2610);
PAINT ORANGE (1240 2610);
FORCEPROP 2 LASTPIN (1250 2550) $PN 46
J 2
(1240 2560);
DISPLAY 0.617021 (1240 2560);
PAINT ORANGE (1240 2560);
FORCEPROP 2 LASTPIN (1250 2500) $PN 48
J 2
(1240 2510);
DISPLAY 0.617021 (1240 2510);
PAINT ORANGE (1240 2510);
FORCEPROP 2 LASTPIN (1250 2450) $PN 50
J 2
(1240 2460);
DISPLAY 0.617021 (1240 2460);
PAINT ORANGE (1240 2460);
FORCEPROP 2 LASTPIN (1250 2400) $PN 53
J 2
(1240 2410);
DISPLAY 0.617021 (1240 2410);
PAINT ORANGE (1240 2410);
FORCEPROP 2 LASTPIN (1250 2350) $PN 55
J 2
(1240 2360);
DISPLAY 0.617021 (1240 2360);
PAINT ORANGE (1240 2360);
FORCEPROP 2 LASTPIN (1250 2300) $PN 57
J 2
(1240 2310);
DISPLAY 0.617021 (1240 2310);
PAINT ORANGE (1240 2310);
FORCEPROP 2 LASTPIN (1250 2250) $PN 94
J 2
(1240 2260);
DISPLAY 0.617021 (1240 2260);
PAINT ORANGE (1240 2260);
FORCEPROP 2 LASTPIN (1250 2200) $PN 96
J 2
(1240 2210);
DISPLAY 0.617021 (1240 2210);
PAINT ORANGE (1240 2210);
FORCEPROP 2 LASTPIN (1250 2150) $PN 98
J 2
(1240 2160);
DISPLAY 0.617021 (1240 2160);
PAINT ORANGE (1240 2160);
FORCEPROP 2 LASTPIN (1250 2100) $PN 101
J 2
(1240 2110);
DISPLAY 0.617021 (1240 2110);
PAINT ORANGE (1240 2110);
FORCEPROP 2 LASTPIN (1250 2050) $PN 103
J 2
(1240 2060);
DISPLAY 0.617021 (1240 2060);
PAINT ORANGE (1240 2060);
FORCEPROP 2 LASTPIN (1250 2000) $PN 105
J 2
(1240 2010);
DISPLAY 0.617021 (1240 2010);
PAINT ORANGE (1240 2010);
FORCEPROP 2 LASTPIN (1250 1950) $PN 107
J 2
(1240 1960);
DISPLAY 0.617021 (1240 1960);
PAINT ORANGE (1240 1960);
FORCEPROP 2 LASTPIN (1250 1900) $PN 109
J 2
(1240 1910);
DISPLAY 0.617021 (1240 1910);
PAINT ORANGE (1240 1910);
FORCEPROP 2 LASTPIN (1250 1850) $PN 112
J 2
(1240 1860);
DISPLAY 0.617021 (1240 1860);
PAINT ORANGE (1240 1860);
FORCEPROP 2 LASTPIN (1250 1800) $PN 114
J 2
(1240 1810);
DISPLAY 0.617021 (1240 1810);
PAINT ORANGE (1240 1810);
FORCEPROP 2 LASTPIN (1250 1750) $PN 116
J 2
(1240 1760);
DISPLAY 0.617021 (1240 1760);
PAINT ORANGE (1240 1760);
FORCEPROP 2 LASTPIN (1250 1700) $PN 118
J 2
(1240 1710);
DISPLAY 0.617021 (1240 1710);
PAINT ORANGE (1240 1710);
FORCEPROP 2 LASTPIN (1250 1650) $PN 120
J 2
(1240 1660);
DISPLAY 0.617021 (1240 1660);
PAINT ORANGE (1240 1660);
FORCEPROP 2 LASTPIN (1250 1600) $PN 123
J 2
(1240 1610);
DISPLAY 0.617021 (1240 1610);
PAINT ORANGE (1240 1610);
FORCEPROP 2 LASTPIN (1250 1550) $PN 125
J 2
(1240 1560);
DISPLAY 0.617021 (1240 1560);
PAINT ORANGE (1240 1560);
FORCEPROP 2 LASTPIN (1250 1500) $PN 127
J 2
(1240 1510);
DISPLAY 0.617021 (1240 1510);
PAINT ORANGE (1240 1510);
FORCEPROP 2 LASTPIN (1250 1450) $PN 129
J 2
(1240 1460);
DISPLAY 0.617021 (1240 1460);
PAINT ORANGE (1240 1460);
FORCEPROP 2 LASTPIN (1250 1400) $PN 131
J 2
(1240 1410);
DISPLAY 0.617021 (1240 1410);
PAINT ORANGE (1240 1410);
FORCEPROP 2 LASTPIN (1250 1350) $PN 134
J 2
(1240 1360);
DISPLAY 0.617021 (1240 1360);
PAINT ORANGE (1240 1360);
FORCEPROP 2 LASTPIN (1250 1300) $PN 136
J 2
(1240 1310);
DISPLAY 0.617021 (1240 1310);
PAINT ORANGE (1240 1310);
FORCEPROP 2 LASTPIN (1250 1250) $PN 138
J 2
(1240 1260);
DISPLAY 0.617021 (1240 1260);
PAINT ORANGE (1240 1260);
FORCEPROP 2 LASTPIN (2250 3550) $PN 147
J 0
(2260 3560);
DISPLAY 0.617021 (2260 3560);
PAINT ORANGE (2260 3560);
FORCEPROP 2 LASTPIN (2250 3500) $PN 149
J 0
(2260 3510);
DISPLAY 0.617021 (2260 3510);
PAINT ORANGE (2260 3510);
FORCEPROP 2 LASTPIN (2250 3450) $PN 151
J 0
(2260 3460);
DISPLAY 0.617021 (2260 3460);
PAINT ORANGE (2260 3460);
FORCEPROP 2 LASTPIN (2250 3400) $PN 154
J 0
(2260 3410);
DISPLAY 0.617021 (2260 3410);
PAINT ORANGE (2260 3410);
FORCEPROP 2 LASTPIN (2250 3350) $PN 156
J 0
(2260 3360);
DISPLAY 0.617021 (2260 3360);
PAINT ORANGE (2260 3360);
FORCEPROP 2 LASTPIN (2250 3300) $PN 158
J 0
(2260 3310);
DISPLAY 0.617021 (2260 3310);
PAINT ORANGE (2260 3310);
FORCEPROP 2 LASTPIN (2250 3250) $PN 160
J 0
(2260 3260);
DISPLAY 0.617021 (2260 3260);
PAINT ORANGE (2260 3260);
FORCEPROP 2 LASTPIN (2250 3200) $PN 162
J 0
(2260 3210);
DISPLAY 0.617021 (2260 3210);
PAINT ORANGE (2260 3210);
FORCEPROP 2 LASTPIN (2250 3150) $PN 165
J 0
(2260 3160);
DISPLAY 0.617021 (2260 3160);
PAINT ORANGE (2260 3160);
FORCEPROP 2 LASTPIN (2250 3100) $PN 167
J 0
(2260 3110);
DISPLAY 0.617021 (2260 3110);
PAINT ORANGE (2260 3110);
FORCEPROP 2 LASTPIN (2250 3050) $PN 169
J 0
(2260 3060);
DISPLAY 0.617021 (2260 3060);
PAINT ORANGE (2260 3060);
FORCEPROP 2 LASTPIN (2250 3000) $PN 171
J 0
(2260 3010);
DISPLAY 0.617021 (2260 3010);
PAINT ORANGE (2260 3010);
FORCEPROP 2 LASTPIN (2250 2950) $PN 173
J 0
(2260 2960);
DISPLAY 0.617021 (2260 2960);
PAINT ORANGE (2260 2960);
FORCEPROP 2 LASTPIN (2250 2900) $PN 176
J 0
(2260 2910);
DISPLAY 0.617021 (2260 2910);
PAINT ORANGE (2260 2910);
FORCEPROP 2 LASTPIN (2250 2850) $PN 178
J 0
(2260 2860);
DISPLAY 0.617021 (2260 2860);
PAINT ORANGE (2260 2860);
FORCEPROP 2 LASTPIN (2250 2800) $PN 180
J 0
(2260 2810);
DISPLAY 0.617021 (2260 2810);
PAINT ORANGE (2260 2810);
FORCEPROP 2 LASTPIN (2250 2750) $PN 182
J 0
(2260 2760);
DISPLAY 0.617021 (2260 2760);
PAINT ORANGE (2260 2760);
FORCEPROP 2 LASTPIN (2250 2700) $PN 184
J 0
(2260 2710);
DISPLAY 0.617021 (2260 2710);
PAINT ORANGE (2260 2710);
FORCEPROP 2 LASTPIN (2250 2650) $PN 187
J 0
(2260 2660);
DISPLAY 0.617021 (2260 2660);
PAINT ORANGE (2260 2660);
FORCEPROP 2 LASTPIN (2250 2600) $PN 189
J 0
(2260 2610);
DISPLAY 0.617021 (2260 2610);
PAINT ORANGE (2260 2610);
FORCEPROP 2 LASTPIN (2250 2550) $PN 191
J 0
(2260 2560);
DISPLAY 0.617021 (2260 2560);
PAINT ORANGE (2260 2560);
FORCEPROP 2 LASTPIN (2250 2500) $PN 193
J 0
(2260 2510);
DISPLAY 0.617021 (2260 2510);
PAINT ORANGE (2260 2510);
FORCEPROP 2 LASTPIN (2250 2450) $PN 195
J 0
(2260 2460);
DISPLAY 0.617021 (2260 2460);
PAINT ORANGE (2260 2460);
FORCEPROP 2 LASTPIN (2250 2400) $PN 198
J 0
(2260 2410);
DISPLAY 0.617021 (2260 2410);
PAINT ORANGE (2260 2410);
FORCEPROP 2 LASTPIN (2250 2350) $PN 200
J 0
(2260 2360);
DISPLAY 0.617021 (2260 2360);
PAINT ORANGE (2260 2360);
FORCEPROP 2 LASTPIN (2250 2300) $PN 202
J 0
(2260 2310);
DISPLAY 0.617021 (2260 2310);
PAINT ORANGE (2260 2310);
FORCEPROP 2 LASTPIN (2250 2250) $PN 239
J 0
(2260 2260);
DISPLAY 0.617021 (2260 2260);
PAINT ORANGE (2260 2260);
FORCEPROP 2 LASTPIN (2250 2200) $PN 241
J 0
(2260 2210);
DISPLAY 0.617021 (2260 2210);
PAINT ORANGE (2260 2210);
FORCEPROP 2 LASTPIN (2250 2150) $PN 243
J 0
(2260 2160);
DISPLAY 0.617021 (2260 2160);
PAINT ORANGE (2260 2160);
FORCEPROP 2 LASTPIN (2250 2100) $PN 246
J 0
(2260 2110);
DISPLAY 0.617021 (2260 2110);
PAINT ORANGE (2260 2110);
FORCEPROP 2 LASTPIN (2250 2050) $PN 248
J 0
(2260 2060);
DISPLAY 0.617021 (2260 2060);
PAINT ORANGE (2260 2060);
FORCEPROP 2 LASTPIN (2250 2000) $PN 250
J 0
(2260 2010);
DISPLAY 0.617021 (2260 2010);
PAINT ORANGE (2260 2010);
FORCEPROP 2 LASTPIN (2250 1950) $PN 252
J 0
(2260 1960);
DISPLAY 0.617021 (2260 1960);
PAINT ORANGE (2260 1960);
FORCEPROP 2 LASTPIN (2250 1900) $PN 254
J 0
(2260 1910);
DISPLAY 0.617021 (2260 1910);
PAINT ORANGE (2260 1910);
FORCEPROP 2 LASTPIN (2250 1850) $PN 257
J 0
(2260 1860);
DISPLAY 0.617021 (2260 1860);
PAINT ORANGE (2260 1860);
FORCEPROP 2 LASTPIN (2250 1800) $PN 259
J 0
(2260 1810);
DISPLAY 0.617021 (2260 1810);
PAINT ORANGE (2260 1810);
FORCEPROP 2 LASTPIN (2250 1750) $PN 261
J 0
(2260 1760);
DISPLAY 0.617021 (2260 1760);
PAINT ORANGE (2260 1760);
FORCEPROP 2 LASTPIN (2250 1700) $PN 263
J 0
(2260 1710);
DISPLAY 0.617021 (2260 1710);
PAINT ORANGE (2260 1710);
FORCEPROP 2 LASTPIN (2250 1650) $PN 265
J 0
(2260 1660);
DISPLAY 0.617021 (2260 1660);
PAINT ORANGE (2260 1660);
FORCEPROP 2 LASTPIN (2250 1600) $PN 268
J 0
(2260 1610);
DISPLAY 0.617021 (2260 1610);
PAINT ORANGE (2260 1610);
FORCEPROP 2 LASTPIN (2250 1550) $PN 270
J 0
(2260 1560);
DISPLAY 0.617021 (2260 1560);
PAINT ORANGE (2260 1560);
FORCEPROP 2 LASTPIN (2250 1500) $PN 272
J 0
(2260 1510);
DISPLAY 0.617021 (2260 1510);
PAINT ORANGE (2260 1510);
FORCEPROP 2 LASTPIN (2250 1450) $PN 274
J 0
(2260 1460);
DISPLAY 0.617021 (2260 1460);
PAINT ORANGE (2260 1460);
FORCEPROP 2 LASTPIN (2250 1400) $PN 276
J 0
(2260 1410);
DISPLAY 0.617021 (2260 1410);
PAINT ORANGE (2260 1410);
FORCEPROP 2 LASTPIN (2250 1350) $PN 279
J 0
(2260 1360);
DISPLAY 0.617021 (2260 1360);
PAINT ORANGE (2260 1360);
FORCEPROP 2 LASTPIN (2250 1300) $PN 281
J 0
(2260 1310);
DISPLAY 0.617021 (2260 1310);
PAINT ORANGE (2260 1310);
FORCEPROP 2 LASTPIN (2250 1250) $PN 283
J 0
(2260 1260);
DISPLAY 0.617021 (2260 1260);
PAINT ORANGE (2260 1260);
FORCEPROP 1 LAST PACK_TYPE PIP
J 0
(1300 3850);
PAINT SKYBLUE (1300 3850);
DISPLAY INVISIBLE (1300 3850);
FORCEPROP 2 LAST BOM_COST MEM
J 0
(1750 2400);
PAINT ORANGE (1750 2400);
DISPLAY INVISIBLE (1750 2400);
FORCEPROP 2 LAST CDS_LIB mstr_sconn
J 0
(1750 2400);
PAINT ORANGE (1750 2400);
DISPLAY INVISIBLE (1750 2400);
FORCEPROP 2 LAST SEC_TYPE PIP
J 0
(1300 3850);
DISPLAY 1.021277 (1300 3850);
PAINT ORANGE (1300 3850);
DISPLAY INVISIBLE (1300 3850);
FORCEPROP 2 LAST SEC 3
J 0
(1300 3850);
DISPLAY 0.680851 (1300 3850);
PAINT MONO (1300 3850);
DISPLAY INVISIBLE (1300 3850);
FORCEPROP 2 LAST CDS_LOCATION J1G2
J 0
(1300 3800);
DISPLAY 0.617021 (1300 3800);
PAINT AQUA (1300 3800);
DISPLAY INVISIBLE (1300 3800);
FORCEPROP 1 LAST PATH I43
J 0
(1750 3750);
PAINT GREEN (1750 3750);
DISPLAY INVISIBLE (1750 3750);
FORCEPROP 2 LAST ROOM DDR4_CH_H
J 0
(1750 2400);
PAINT ORANGE (1750 2400);
DISPLAY INVISIBLE (1750 2400);
FORCEADD GND..1
R 2
(1050 1100);
FORCEPROP 3 LASTPIN (1050 1150) SIG_NAME GND\g
J 0
(1060 1160);
DISPLAY 0.659574 (1060 1160);
PAINT MONO (1060 1160);
DISPLAY INVISIBLE (1060 1160);
FORCEPROP 1 LAST VOLTAGE 0
J 0
(1050 1100);
PAINT SKYBLUE (1050 1100);
DISPLAY INVISIBLE (1050 1100);
FORCEPROP 2 LAST CDS_LIB mstr_symbols
J 0
(1050 1100);
DISPLAY 0.787234 (1050 1100);
PAINT MONO (1050 1100);
DISPLAY INVISIBLE (1050 1100);
FORCEPROP 1 LAST SIZE 1B
J 2
(975 1050);
DISPLAY 1.170213 (975 1050);
PAINT GREEN (975 1050);
DISPLAY INVISIBLE (975 1050);
FORCEPROP 2 LAST BOM_COST MEM
J 0
(1050 1105);
PAINT ORANGE (1050 1105);
DISPLAY INVISIBLE (1050 1105);
FORCEPROP 1 LAST BODY_TYPE PLUMBING
J 2
(1095 1057);
DISPLAY 0.340426 (1095 1057);
PAINT GREEN (1095 1057);
DISPLAY INVISIBLE (1095 1057);
FORCEPROP 1 LAST PATH I44
J 2
(975 1100);
DISPLAY 0.936170 (975 1100);
PAINT GREEN (975 1100);
DISPLAY INVISIBLE (975 1100);
FORCEPROP 2 LAST ROOM DDR4_CH_H
J 0
(1050 1105);
PAINT ORANGE (1050 1105);
DISPLAY INVISIBLE (1050 1105);
FORCEPROP 1 LAST HDL_POWER GND
J 2
(1050 1250);
DISPLAY 0.553191 (1050 1250);
PAINT GREEN (1050 1250);
DISPLAY INVISIBLE (1050 1250);
FORCEADD OFFPAGE..3
(-1250 4950);
FORCEPROP 2 LAST $XR0 58 
J 0
(-1036 4950);
DISPLAY 0.638298 (-1036 4950);
PAINT MONO (-1036 4950);
FORCEPROP 2 LAST $XR1 80 
J 0
(-946 4950);
DISPLAY 0.638298 (-946 4950);
PAINT MONO (-946 4950);
FORCEPROP 2 LAST CDS_LIB mstr_standard
J 0
(-1250 4950);
DISPLAY 0.787234 (-1250 4950);
PAINT MONO (-1250 4950);
DISPLAY INVISIBLE (-1250 4950);
FORCEPROP 1 LAST OFFPAGE TRUE
J 0
(-925 4825);
DISPLAY 0.936170 (-925 4825);
PAINT GREEN (-925 4825);
DISPLAY INVISIBLE (-925 4825);
FORCEPROP 1 LAST COMMENT_BODY TRUE
J 0
(-1300 4850);
DISPLAY 0.936170 (-1300 4850);
PAINT GREEN (-1300 4850);
DISPLAY INVISIBLE (-1300 4850);
FORCEPROP 2 LAST PATH I45
J 0
(-1050 5025);
DISPLAY 0.787234 (-1050 5025);
PAINT MONO (-1050 5025);
DISPLAY INVISIBLE (-1050 5025);
FORCEADD TAP..6
R 2
(-1850 4850);
FORCEPROP 3 LASTPIN (-1900 4850) SIG_NAME M_H_DQ<63>
J 0
(-1890 4860);
DISPLAY 0.659574 (-1890 4860);
PAINT MONO (-1890 4860);
DISPLAY INVISIBLE (-1890 4860);
FORCEPROP 1 LASTPIN (-1900 4850) BN 63
J 2
(-1850 4860);
DISPLAY 0.617021 (-1850 4860);
PAINT PINK (-1850 4860);
FORCEPROP 2 LAST CDS_LIB mstr_standard
J 2
(-1850 4850);
DISPLAY 0.787234 (-1850 4850);
PAINT MONO (-1850 4850);
DISPLAY INVISIBLE (-1850 4850);
FORCEPROP 1 LAST BODY_TYPE PLUMBING
J 2
(-1850 4800);
DISPLAY 1.234043 (-1850 4800);
PAINT GREEN (-1850 4800);
DISPLAY INVISIBLE (-1850 4800);
FORCEPROP 1 LAST HDL_TAP TRUE
J 2
(-2175 4725);
DISPLAY 1.234043 (-2175 4725);
PAINT GREEN (-2175 4725);
DISPLAY INVISIBLE (-2175 4725);
FORCEPROP 1 LAST PATH I46
J 2
(-1850 4850);
DISPLAY 0.936170 (-1850 4850);
PAINT GREEN (-1850 4850);
DISPLAY INVISIBLE (-1850 4850);
FORCEADD TAP..6
R 2
(-1850 4900);
FORCEPROP 3 LASTPIN (-1900 4900) SIG_NAME M_H_DQ<62>
J 0
(-1890 4910);
DISPLAY 0.659574 (-1890 4910);
PAINT MONO (-1890 4910);
DISPLAY INVISIBLE (-1890 4910);
FORCEPROP 1 LASTPIN (-1900 4900) BN 62
J 2
(-1850 4910);
DISPLAY 0.617021 (-1850 4910);
PAINT PINK (-1850 4910);
FORCEPROP 2 LAST CDS_LIB mstr_standard
J 2
(-1850 4900);
DISPLAY 0.787234 (-1850 4900);
PAINT MONO (-1850 4900);
DISPLAY INVISIBLE (-1850 4900);
FORCEPROP 1 LAST BODY_TYPE PLUMBING
J 2
(-1850 4850);
DISPLAY 1.234043 (-1850 4850);
PAINT GREEN (-1850 4850);
DISPLAY INVISIBLE (-1850 4850);
FORCEPROP 1 LAST HDL_TAP TRUE
J 2
(-2175 4775);
DISPLAY 1.234043 (-2175 4775);
PAINT GREEN (-2175 4775);
DISPLAY INVISIBLE (-2175 4775);
FORCEPROP 1 LAST PATH I47
J 2
(-1850 4900);
DISPLAY 0.936170 (-1850 4900);
PAINT GREEN (-1850 4900);
DISPLAY INVISIBLE (-1850 4900);
FORCEADD TAP..6
R 2
(-1850 4750);
FORCEPROP 3 LASTPIN (-1900 4750) SIG_NAME M_H_DQ<61>
J 0
(-1890 4760);
DISPLAY 0.659574 (-1890 4760);
PAINT MONO (-1890 4760);
DISPLAY INVISIBLE (-1890 4760);
FORCEPROP 1 LASTPIN (-1900 4750) BN 61
J 2
(-1850 4760);
DISPLAY 0.617021 (-1850 4760);
PAINT PINK (-1850 4760);
FORCEPROP 2 LAST CDS_LIB mstr_standard
J 2
(-1850 4750);
DISPLAY 0.787234 (-1850 4750);
PAINT MONO (-1850 4750);
DISPLAY INVISIBLE (-1850 4750);
FORCEPROP 1 LAST BODY_TYPE PLUMBING
J 2
(-1850 4700);
DISPLAY 1.234043 (-1850 4700);
PAINT GREEN (-1850 4700);
DISPLAY INVISIBLE (-1850 4700);
FORCEPROP 1 LAST HDL_TAP TRUE
J 2
(-2175 4625);
DISPLAY 1.234043 (-2175 4625);
PAINT GREEN (-2175 4625);
DISPLAY INVISIBLE (-2175 4625);
FORCEPROP 1 LAST PATH I48
J 2
(-1850 4750);
DISPLAY 0.936170 (-1850 4750);
PAINT GREEN (-1850 4750);
DISPLAY INVISIBLE (-1850 4750);
FORCEADD TAP..6
R 2
(-1850 4800);
FORCEPROP 3 LASTPIN (-1900 4800) SIG_NAME M_H_DQ<60>
J 0
(-1890 4810);
DISPLAY 0.659574 (-1890 4810);
PAINT MONO (-1890 4810);
DISPLAY INVISIBLE (-1890 4810);
FORCEPROP 1 LASTPIN (-1900 4800) BN 60
J 2
(-1850 4810);
DISPLAY 0.617021 (-1850 4810);
PAINT PINK (-1850 4810);
FORCEPROP 2 LAST CDS_LIB mstr_standard
J 2
(-1850 4800);
DISPLAY 0.787234 (-1850 4800);
PAINT MONO (-1850 4800);
DISPLAY INVISIBLE (-1850 4800);
FORCEPROP 1 LAST BODY_TYPE PLUMBING
J 2
(-1850 4750);
DISPLAY 1.234043 (-1850 4750);
PAINT GREEN (-1850 4750);
DISPLAY INVISIBLE (-1850 4750);
FORCEPROP 1 LAST HDL_TAP TRUE
J 2
(-2175 4675);
DISPLAY 1.234043 (-2175 4675);
PAINT GREEN (-2175 4675);
DISPLAY INVISIBLE (-2175 4675);
FORCEPROP 1 LAST PATH I49
J 2
(-1850 4800);
DISPLAY 0.936170 (-1850 4800);
PAINT GREEN (-1850 4800);
DISPLAY INVISIBLE (-1850 4800);
FORCEADD TAP..6
R 2
(850 4900);
FORCEPROP 3 LASTPIN (800 4900) SIG_NAME M_H_DQS_DN<15>
J 0
(810 4910);
DISPLAY 0.659574 (810 4910);
PAINT MONO (810 4910);
DISPLAY INVISIBLE (810 4910);
FORCEPROP 1 LASTPIN (800 4900) BN 15
J 2
(850 4910);
DISPLAY 0.617021 (850 4910);
PAINT PINK (850 4910);
FORCEPROP 2 LAST CDS_LIB mstr_standard
J 0
(850 4900);
DISPLAY 0.787234 (850 4900);
PAINT MONO (850 4900);
DISPLAY INVISIBLE (850 4900);
FORCEPROP 1 LAST BODY_TYPE PLUMBING
J 2
(850 4850);
DISPLAY 1.234043 (850 4850);
PAINT GREEN (850 4850);
DISPLAY INVISIBLE (850 4850);
FORCEPROP 1 LAST HDL_TAP TRUE
J 2
(525 4775);
DISPLAY 1.234043 (525 4775);
PAINT GREEN (525 4775);
DISPLAY INVISIBLE (525 4775);
FORCEPROP 1 LAST PATH I5
J 2
(850 4900);
DISPLAY 0.936170 (850 4900);
PAINT GREEN (850 4900);
DISPLAY INVISIBLE (850 4900);
FORCEADD TAP..6
R 2
(-1850 4700);
FORCEPROP 3 LASTPIN (-1900 4700) SIG_NAME M_H_DQ<58>
J 0
(-1890 4710);
DISPLAY 0.659574 (-1890 4710);
PAINT MONO (-1890 4710);
DISPLAY INVISIBLE (-1890 4710);
FORCEPROP 1 LASTPIN (-1900 4700) BN 58
J 2
(-1850 4710);
DISPLAY 0.617021 (-1850 4710);
PAINT PINK (-1850 4710);
FORCEPROP 2 LAST CDS_LIB mstr_standard
J 2
(-1850 4700);
DISPLAY 0.787234 (-1850 4700);
PAINT MONO (-1850 4700);
DISPLAY INVISIBLE (-1850 4700);
FORCEPROP 1 LAST BODY_TYPE PLUMBING
J 2
(-1850 4650);
DISPLAY 1.234043 (-1850 4650);
PAINT GREEN (-1850 4650);
DISPLAY INVISIBLE (-1850 4650);
FORCEPROP 1 LAST HDL_TAP TRUE
J 2
(-2175 4575);
DISPLAY 1.234043 (-2175 4575);
PAINT GREEN (-2175 4575);
DISPLAY INVISIBLE (-2175 4575);
FORCEPROP 1 LAST PATH I50
J 2
(-1850 4700);
DISPLAY 0.936170 (-1850 4700);
PAINT GREEN (-1850 4700);
DISPLAY INVISIBLE (-1850 4700);
FORCEADD TAP..6
R 2
(-1850 4650);
FORCEPROP 3 LASTPIN (-1900 4650) SIG_NAME M_H_DQ<59>
J 0
(-1890 4660);
DISPLAY 0.659574 (-1890 4660);
PAINT MONO (-1890 4660);
DISPLAY INVISIBLE (-1890 4660);
FORCEPROP 1 LASTPIN (-1900 4650) BN 59
J 2
(-1850 4660);
DISPLAY 0.617021 (-1850 4660);
PAINT PINK (-1850 4660);
FORCEPROP 2 LAST CDS_LIB mstr_standard
J 2
(-1850 4650);
DISPLAY 0.787234 (-1850 4650);
PAINT MONO (-1850 4650);
DISPLAY INVISIBLE (-1850 4650);
FORCEPROP 1 LAST BODY_TYPE PLUMBING
J 2
(-1850 4600);
DISPLAY 1.234043 (-1850 4600);
PAINT GREEN (-1850 4600);
DISPLAY INVISIBLE (-1850 4600);
FORCEPROP 1 LAST HDL_TAP TRUE
J 2
(-2175 4525);
DISPLAY 1.234043 (-2175 4525);
PAINT GREEN (-2175 4525);
DISPLAY INVISIBLE (-2175 4525);
FORCEPROP 1 LAST PATH I51
J 2
(-1850 4650);
DISPLAY 0.936170 (-1850 4650);
PAINT GREEN (-1850 4650);
DISPLAY INVISIBLE (-1850 4650);
FORCEADD TAP..6
R 2
(-1850 4600);
FORCEPROP 3 LASTPIN (-1900 4600) SIG_NAME M_H_DQ<56>
J 0
(-1890 4610);
DISPLAY 0.659574 (-1890 4610);
PAINT MONO (-1890 4610);
DISPLAY INVISIBLE (-1890 4610);
FORCEPROP 1 LASTPIN (-1900 4600) BN 56
J 2
(-1850 4610);
DISPLAY 0.617021 (-1850 4610);
PAINT PINK (-1850 4610);
FORCEPROP 2 LAST CDS_LIB mstr_standard
J 2
(-1850 4600);
DISPLAY 0.787234 (-1850 4600);
PAINT MONO (-1850 4600);
DISPLAY INVISIBLE (-1850 4600);
FORCEPROP 1 LAST BODY_TYPE PLUMBING
J 2
(-1850 4550);
DISPLAY 1.234043 (-1850 4550);
PAINT GREEN (-1850 4550);
DISPLAY INVISIBLE (-1850 4550);
FORCEPROP 1 LAST HDL_TAP TRUE
J 2
(-2175 4475);
DISPLAY 1.234043 (-2175 4475);
PAINT GREEN (-2175 4475);
DISPLAY INVISIBLE (-2175 4475);
FORCEPROP 1 LAST PATH I52
J 2
(-1850 4600);
DISPLAY 0.936170 (-1850 4600);
PAINT GREEN (-1850 4600);
DISPLAY INVISIBLE (-1850 4600);
FORCEADD TAP..6
R 2
(-1850 4400);
FORCEPROP 3 LASTPIN (-1900 4400) SIG_NAME M_H_DQ<52>
J 0
(-1890 4410);
DISPLAY 0.659574 (-1890 4410);
PAINT MONO (-1890 4410);
DISPLAY INVISIBLE (-1890 4410);
FORCEPROP 1 LASTPIN (-1900 4400) BN 52
J 2
(-1850 4410);
DISPLAY 0.617021 (-1850 4410);
PAINT PINK (-1850 4410);
FORCEPROP 2 LAST CDS_LIB mstr_standard
J 2
(-1850 4400);
DISPLAY 0.787234 (-1850 4400);
PAINT MONO (-1850 4400);
DISPLAY INVISIBLE (-1850 4400);
FORCEPROP 1 LAST BODY_TYPE PLUMBING
J 2
(-1850 4350);
DISPLAY 1.234043 (-1850 4350);
PAINT GREEN (-1850 4350);
DISPLAY INVISIBLE (-1850 4350);
FORCEPROP 1 LAST HDL_TAP TRUE
J 2
(-2175 4275);
DISPLAY 1.234043 (-2175 4275);
PAINT GREEN (-2175 4275);
DISPLAY INVISIBLE (-2175 4275);
FORCEPROP 1 LAST PATH I53
J 2
(-1850 4400);
DISPLAY 0.936170 (-1850 4400);
PAINT GREEN (-1850 4400);
DISPLAY INVISIBLE (-1850 4400);
FORCEADD TAP..6
R 2
(-1850 4450);
FORCEPROP 3 LASTPIN (-1900 4450) SIG_NAME M_H_DQ<55>
J 0
(-1890 4460);
DISPLAY 0.659574 (-1890 4460);
PAINT MONO (-1890 4460);
DISPLAY INVISIBLE (-1890 4460);
FORCEPROP 1 LASTPIN (-1900 4450) BN 55
J 2
(-1850 4460);
DISPLAY 0.617021 (-1850 4460);
PAINT PINK (-1850 4460);
FORCEPROP 2 LAST CDS_LIB mstr_standard
J 2
(-1850 4450);
DISPLAY 0.787234 (-1850 4450);
PAINT MONO (-1850 4450);
DISPLAY INVISIBLE (-1850 4450);
FORCEPROP 1 LAST BODY_TYPE PLUMBING
J 2
(-1850 4400);
DISPLAY 1.234043 (-1850 4400);
PAINT GREEN (-1850 4400);
DISPLAY INVISIBLE (-1850 4400);
FORCEPROP 1 LAST HDL_TAP TRUE
J 2
(-2175 4325);
DISPLAY 1.234043 (-2175 4325);
PAINT GREEN (-2175 4325);
DISPLAY INVISIBLE (-2175 4325);
FORCEPROP 1 LAST PATH I54
J 2
(-1850 4450);
DISPLAY 0.936170 (-1850 4450);
PAINT GREEN (-1850 4450);
DISPLAY INVISIBLE (-1850 4450);
FORCEADD TAP..6
R 2
(-1850 4350);
FORCEPROP 3 LASTPIN (-1900 4350) SIG_NAME M_H_DQ<53>
J 0
(-1890 4360);
DISPLAY 0.659574 (-1890 4360);
PAINT MONO (-1890 4360);
DISPLAY INVISIBLE (-1890 4360);
FORCEPROP 1 LASTPIN (-1900 4350) BN 53
J 2
(-1850 4360);
DISPLAY 0.617021 (-1850 4360);
PAINT PINK (-1850 4360);
FORCEPROP 2 LAST CDS_LIB mstr_standard
J 2
(-1850 4350);
DISPLAY 0.787234 (-1850 4350);
PAINT MONO (-1850 4350);
DISPLAY INVISIBLE (-1850 4350);
FORCEPROP 1 LAST BODY_TYPE PLUMBING
J 2
(-1850 4300);
DISPLAY 1.234043 (-1850 4300);
PAINT GREEN (-1850 4300);
DISPLAY INVISIBLE (-1850 4300);
FORCEPROP 1 LAST HDL_TAP TRUE
J 2
(-2175 4225);
DISPLAY 1.234043 (-2175 4225);
PAINT GREEN (-2175 4225);
DISPLAY INVISIBLE (-2175 4225);
FORCEPROP 1 LAST PATH I55
J 2
(-1850 4350);
DISPLAY 0.936170 (-1850 4350);
PAINT GREEN (-1850 4350);
DISPLAY INVISIBLE (-1850 4350);
FORCEADD TAP..6
R 2
(-1850 4500);
FORCEPROP 3 LASTPIN (-1900 4500) SIG_NAME M_H_DQ<54>
J 0
(-1890 4510);
DISPLAY 0.659574 (-1890 4510);
PAINT MONO (-1890 4510);
DISPLAY INVISIBLE (-1890 4510);
FORCEPROP 1 LASTPIN (-1900 4500) BN 54
J 2
(-1850 4510);
DISPLAY 0.617021 (-1850 4510);
PAINT PINK (-1850 4510);
FORCEPROP 2 LAST CDS_LIB mstr_standard
J 2
(-1850 4500);
DISPLAY 0.787234 (-1850 4500);
PAINT MONO (-1850 4500);
DISPLAY INVISIBLE (-1850 4500);
FORCEPROP 1 LAST BODY_TYPE PLUMBING
J 2
(-1850 4450);
DISPLAY 1.234043 (-1850 4450);
PAINT GREEN (-1850 4450);
DISPLAY INVISIBLE (-1850 4450);
FORCEPROP 1 LAST HDL_TAP TRUE
J 2
(-2175 4375);
DISPLAY 1.234043 (-2175 4375);
PAINT GREEN (-2175 4375);
DISPLAY INVISIBLE (-2175 4375);
FORCEPROP 1 LAST PATH I56
J 2
(-1850 4500);
DISPLAY 0.936170 (-1850 4500);
PAINT GREEN (-1850 4500);
DISPLAY INVISIBLE (-1850 4500);
FORCEADD TAP..6
R 2
(-1850 4550);
FORCEPROP 3 LASTPIN (-1900 4550) SIG_NAME M_H_DQ<57>
J 0
(-1890 4560);
DISPLAY 0.659574 (-1890 4560);
PAINT MONO (-1890 4560);
DISPLAY INVISIBLE (-1890 4560);
FORCEPROP 1 LASTPIN (-1900 4550) BN 57
J 2
(-1850 4560);
DISPLAY 0.617021 (-1850 4560);
PAINT PINK (-1850 4560);
FORCEPROP 2 LAST CDS_LIB mstr_standard
J 2
(-1850 4550);
DISPLAY 0.787234 (-1850 4550);
PAINT MONO (-1850 4550);
DISPLAY INVISIBLE (-1850 4550);
FORCEPROP 1 LAST BODY_TYPE PLUMBING
J 2
(-1850 4500);
DISPLAY 1.234043 (-1850 4500);
PAINT GREEN (-1850 4500);
DISPLAY INVISIBLE (-1850 4500);
FORCEPROP 1 LAST HDL_TAP TRUE
J 2
(-2175 4425);
DISPLAY 1.234043 (-2175 4425);
PAINT GREEN (-2175 4425);
DISPLAY INVISIBLE (-2175 4425);
FORCEPROP 1 LAST PATH I57
J 2
(-1850 4550);
DISPLAY 0.936170 (-1850 4550);
PAINT GREEN (-1850 4550);
DISPLAY INVISIBLE (-1850 4550);
FORCEADD TAP..6
R 2
(-1850 4100);
FORCEPROP 3 LASTPIN (-1900 4100) SIG_NAME M_H_DQ<46>
J 0
(-1890 4110);
DISPLAY 0.659574 (-1890 4110);
PAINT MONO (-1890 4110);
DISPLAY INVISIBLE (-1890 4110);
FORCEPROP 1 LASTPIN (-1900 4100) BN 46
J 2
(-1850 4110);
DISPLAY 0.617021 (-1850 4110);
PAINT PINK (-1850 4110);
FORCEPROP 2 LAST CDS_LIB mstr_standard
J 2
(-1850 4100);
DISPLAY 0.787234 (-1850 4100);
PAINT MONO (-1850 4100);
DISPLAY INVISIBLE (-1850 4100);
FORCEPROP 1 LAST BODY_TYPE PLUMBING
J 2
(-1850 4050);
DISPLAY 1.234043 (-1850 4050);
PAINT GREEN (-1850 4050);
DISPLAY INVISIBLE (-1850 4050);
FORCEPROP 1 LAST HDL_TAP TRUE
J 2
(-2175 3975);
DISPLAY 1.234043 (-2175 3975);
PAINT GREEN (-2175 3975);
DISPLAY INVISIBLE (-2175 3975);
FORCEPROP 1 LAST PATH I58
J 2
(-1850 4100);
DISPLAY 0.936170 (-1850 4100);
PAINT GREEN (-1850 4100);
DISPLAY INVISIBLE (-1850 4100);
FORCEADD TAP..6
R 2
(-1850 4150);
FORCEPROP 3 LASTPIN (-1900 4150) SIG_NAME M_H_DQ<49>
J 0
(-1890 4160);
DISPLAY 0.659574 (-1890 4160);
PAINT MONO (-1890 4160);
DISPLAY INVISIBLE (-1890 4160);
FORCEPROP 1 LASTPIN (-1900 4150) BN 49
J 2
(-1850 4160);
DISPLAY 0.617021 (-1850 4160);
PAINT PINK (-1850 4160);
FORCEPROP 2 LAST CDS_LIB mstr_standard
J 2
(-1850 4150);
DISPLAY 0.787234 (-1850 4150);
PAINT MONO (-1850 4150);
DISPLAY INVISIBLE (-1850 4150);
FORCEPROP 1 LAST BODY_TYPE PLUMBING
J 2
(-1850 4100);
DISPLAY 1.234043 (-1850 4100);
PAINT GREEN (-1850 4100);
DISPLAY INVISIBLE (-1850 4100);
FORCEPROP 1 LAST HDL_TAP TRUE
J 2
(-2175 4025);
DISPLAY 1.234043 (-2175 4025);
PAINT GREEN (-2175 4025);
DISPLAY INVISIBLE (-2175 4025);
FORCEPROP 1 LAST PATH I59
J 2
(-1850 4150);
DISPLAY 0.936170 (-1850 4150);
PAINT GREEN (-1850 4150);
DISPLAY INVISIBLE (-1850 4150);
FORCEADD TAP..6
R 2
(850 4800);
FORCEPROP 3 LASTPIN (800 4800) SIG_NAME M_H_DQS_DN<14>
J 0
(810 4810);
DISPLAY 0.659574 (810 4810);
PAINT MONO (810 4810);
DISPLAY INVISIBLE (810 4810);
FORCEPROP 1 LASTPIN (800 4800) BN 14
J 2
(850 4810);
DISPLAY 0.617021 (850 4810);
PAINT PINK (850 4810);
FORCEPROP 2 LAST CDS_LIB mstr_standard
J 0
(850 4800);
DISPLAY 0.787234 (850 4800);
PAINT MONO (850 4800);
DISPLAY INVISIBLE (850 4800);
FORCEPROP 1 LAST BODY_TYPE PLUMBING
J 2
(850 4750);
DISPLAY 1.234043 (850 4750);
PAINT GREEN (850 4750);
DISPLAY INVISIBLE (850 4750);
FORCEPROP 1 LAST HDL_TAP TRUE
J 2
(525 4675);
DISPLAY 1.234043 (525 4675);
PAINT GREEN (525 4675);
DISPLAY INVISIBLE (525 4675);
FORCEPROP 1 LAST PATH I6
J 2
(850 4800);
DISPLAY 0.936170 (850 4800);
PAINT GREEN (850 4800);
DISPLAY INVISIBLE (850 4800);
FORCEADD TAP..6
R 2
(-1850 4050);
FORCEPROP 3 LASTPIN (-1900 4050) SIG_NAME M_H_DQ<47>
J 0
(-1890 4060);
DISPLAY 0.659574 (-1890 4060);
PAINT MONO (-1890 4060);
DISPLAY INVISIBLE (-1890 4060);
FORCEPROP 1 LASTPIN (-1900 4050) BN 47
J 2
(-1850 4060);
DISPLAY 0.617021 (-1850 4060);
PAINT PINK (-1850 4060);
FORCEPROP 2 LAST CDS_LIB mstr_standard
J 2
(-1850 4050);
DISPLAY 0.787234 (-1850 4050);
PAINT MONO (-1850 4050);
DISPLAY INVISIBLE (-1850 4050);
FORCEPROP 1 LAST BODY_TYPE PLUMBING
J 2
(-1850 4000);
DISPLAY 1.234043 (-1850 4000);
PAINT GREEN (-1850 4000);
DISPLAY INVISIBLE (-1850 4000);
FORCEPROP 1 LAST HDL_TAP TRUE
J 2
(-2175 3925);
DISPLAY 1.234043 (-2175 3925);
PAINT GREEN (-2175 3925);
DISPLAY INVISIBLE (-2175 3925);
FORCEPROP 1 LAST PATH I60
J 2
(-1850 4050);
DISPLAY 0.936170 (-1850 4050);
PAINT GREEN (-1850 4050);
DISPLAY INVISIBLE (-1850 4050);
FORCEADD TAP..6
R 2
(-1850 4200);
FORCEPROP 3 LASTPIN (-1900 4200) SIG_NAME M_H_DQ<48>
J 0
(-1890 4210);
DISPLAY 0.659574 (-1890 4210);
PAINT MONO (-1890 4210);
DISPLAY INVISIBLE (-1890 4210);
FORCEPROP 1 LASTPIN (-1900 4200) BN 48
J 2
(-1850 4210);
DISPLAY 0.617021 (-1850 4210);
PAINT PINK (-1850 4210);
FORCEPROP 2 LAST CDS_LIB mstr_standard
J 2
(-1850 4200);
DISPLAY 0.787234 (-1850 4200);
PAINT MONO (-1850 4200);
DISPLAY INVISIBLE (-1850 4200);
FORCEPROP 1 LAST BODY_TYPE PLUMBING
J 2
(-1850 4150);
DISPLAY 1.234043 (-1850 4150);
PAINT GREEN (-1850 4150);
DISPLAY INVISIBLE (-1850 4150);
FORCEPROP 1 LAST HDL_TAP TRUE
J 2
(-2175 4075);
DISPLAY 1.234043 (-2175 4075);
PAINT GREEN (-2175 4075);
DISPLAY INVISIBLE (-2175 4075);
FORCEPROP 1 LAST PATH I61
J 2
(-1850 4200);
DISPLAY 0.936170 (-1850 4200);
PAINT GREEN (-1850 4200);
DISPLAY INVISIBLE (-1850 4200);
FORCEADD TAP..6
R 2
(-1850 4250);
FORCEPROP 3 LASTPIN (-1900 4250) SIG_NAME M_H_DQ<51>
J 0
(-1890 4260);
DISPLAY 0.659574 (-1890 4260);
PAINT MONO (-1890 4260);
DISPLAY INVISIBLE (-1890 4260);
FORCEPROP 1 LASTPIN (-1900 4250) BN 51
J 2
(-1850 4260);
DISPLAY 0.617021 (-1850 4260);
PAINT PINK (-1850 4260);
FORCEPROP 2 LAST CDS_LIB mstr_standard
J 2
(-1850 4250);
DISPLAY 0.787234 (-1850 4250);
PAINT MONO (-1850 4250);
DISPLAY INVISIBLE (-1850 4250);
FORCEPROP 1 LAST BODY_TYPE PLUMBING
J 2
(-1850 4200);
DISPLAY 1.234043 (-1850 4200);
PAINT GREEN (-1850 4200);
DISPLAY INVISIBLE (-1850 4200);
FORCEPROP 1 LAST HDL_TAP TRUE
J 2
(-2175 4125);
DISPLAY 1.234043 (-2175 4125);
PAINT GREEN (-2175 4125);
DISPLAY INVISIBLE (-2175 4125);
FORCEPROP 1 LAST PATH I62
J 2
(-1850 4250);
DISPLAY 0.936170 (-1850 4250);
PAINT GREEN (-1850 4250);
DISPLAY INVISIBLE (-1850 4250);
FORCEADD TAP..6
R 2
(-1850 4300);
FORCEPROP 3 LASTPIN (-1900 4300) SIG_NAME M_H_DQ<50>
J 0
(-1890 4310);
DISPLAY 0.659574 (-1890 4310);
PAINT MONO (-1890 4310);
DISPLAY INVISIBLE (-1890 4310);
FORCEPROP 1 LASTPIN (-1900 4300) BN 50
J 2
(-1850 4310);
DISPLAY 0.617021 (-1850 4310);
PAINT PINK (-1850 4310);
FORCEPROP 2 LAST CDS_LIB mstr_standard
J 2
(-1850 4300);
DISPLAY 0.787234 (-1850 4300);
PAINT MONO (-1850 4300);
DISPLAY INVISIBLE (-1850 4300);
FORCEPROP 1 LAST BODY_TYPE PLUMBING
J 2
(-1850 4250);
DISPLAY 1.234043 (-1850 4250);
PAINT GREEN (-1850 4250);
DISPLAY INVISIBLE (-1850 4250);
FORCEPROP 1 LAST HDL_TAP TRUE
J 2
(-2175 4175);
DISPLAY 1.234043 (-2175 4175);
PAINT GREEN (-2175 4175);
DISPLAY INVISIBLE (-2175 4175);
FORCEPROP 1 LAST PATH I63
J 2
(-1850 4300);
DISPLAY 0.936170 (-1850 4300);
PAINT GREEN (-1850 4300);
DISPLAY INVISIBLE (-1850 4300);
FORCEADD SCONN288_H44441004..2
(-50 4300);
FORCEPROP 1 LAST LOCATION J1G2
J 0
(-450 5400);
DISPLAY 0.617021 (-450 5400);
PAINT AQUA (-450 5400);
FORCEPROP 1 LAST PART_NUMBER H44441-004
J 0
(-450 3200);
DISPLAY 0.617021 (-450 3200);
PAINT BLUE (-450 3200);
FORCEPROP 1 LAST MATERIAL SCONN
J 0
(-450 5350);
DISPLAY 0.617021 (-450 5350);
PAINT SKYBLUE (-450 5350);
FORCEPROP 2 LASTPIN (400 5150) $PN 51
J 0
(410 5160);
DISPLAY 0.617021 (410 5160);
PAINT ORANGE (410 5160);
FORCEPROP 2 LASTPIN (400 5100) $PN 52
J 0
(410 5110);
DISPLAY 0.617021 (410 5110);
PAINT ORANGE (410 5110);
FORCEPROP 2 LASTPIN (400 5050) $PN 132
J 0
(410 5060);
DISPLAY 0.617021 (410 5060);
PAINT ORANGE (410 5060);
FORCEPROP 2 LASTPIN (400 5000) $PN 133
J 0
(410 5010);
DISPLAY 0.617021 (410 5010);
PAINT ORANGE (410 5010);
FORCEPROP 2 LASTPIN (400 4950) $PN 121
J 0
(410 4960);
DISPLAY 0.617021 (410 4960);
PAINT ORANGE (410 4960);
FORCEPROP 2 LASTPIN (400 4900) $PN 122
J 0
(410 4910);
DISPLAY 0.617021 (410 4910);
PAINT ORANGE (410 4910);
FORCEPROP 2 LASTPIN (400 4850) $PN 110
J 0
(410 4860);
DISPLAY 0.617021 (410 4860);
PAINT ORANGE (410 4860);
FORCEPROP 2 LASTPIN (400 4800) $PN 111
J 0
(410 4810);
DISPLAY 0.617021 (410 4810);
PAINT ORANGE (410 4810);
FORCEPROP 2 LASTPIN (400 4750) $PN 99
J 0
(410 4760);
DISPLAY 0.617021 (410 4760);
PAINT ORANGE (410 4760);
FORCEPROP 2 LASTPIN (400 4700) $PN 100
J 0
(410 4710);
DISPLAY 0.617021 (410 4710);
PAINT ORANGE (410 4710);
FORCEPROP 2 LASTPIN (400 4650) $PN 40
J 0
(410 4660);
DISPLAY 0.617021 (410 4660);
PAINT ORANGE (410 4660);
FORCEPROP 2 LASTPIN (400 4600) $PN 41
J 0
(410 4610);
DISPLAY 0.617021 (410 4610);
PAINT ORANGE (410 4610);
FORCEPROP 2 LASTPIN (400 4550) $PN 29
J 0
(410 4560);
DISPLAY 0.617021 (410 4560);
PAINT ORANGE (410 4560);
FORCEPROP 2 LASTPIN (400 4500) $PN 30
J 0
(410 4510);
DISPLAY 0.617021 (410 4510);
PAINT ORANGE (410 4510);
FORCEPROP 2 LASTPIN (400 4450) $PN 18
J 0
(410 4460);
DISPLAY 0.617021 (410 4460);
PAINT ORANGE (410 4460);
FORCEPROP 2 LASTPIN (400 4400) $PN 19
J 0
(410 4410);
DISPLAY 0.617021 (410 4410);
PAINT ORANGE (410 4410);
FORCEPROP 2 LASTPIN (400 4350) $PN 7
J 0
(410 4360);
DISPLAY 0.617021 (410 4360);
PAINT ORANGE (410 4360);
FORCEPROP 2 LASTPIN (400 4300) $PN 8
J 0
(410 4310);
DISPLAY 0.617021 (410 4310);
PAINT ORANGE (410 4310);
FORCEPROP 2 LASTPIN (400 4250) $PN 197
J 0
(410 4260);
DISPLAY 0.617021 (410 4260);
PAINT ORANGE (410 4260);
FORCEPROP 2 LASTPIN (400 4200) $PN 196
J 0
(410 4210);
DISPLAY 0.617021 (410 4210);
PAINT ORANGE (410 4210);
FORCEPROP 2 LASTPIN (400 4150) $PN 278
J 0
(410 4160);
DISPLAY 0.617021 (410 4160);
PAINT ORANGE (410 4160);
FORCEPROP 2 LASTPIN (400 4100) $PN 277
J 0
(410 4110);
DISPLAY 0.617021 (410 4110);
PAINT ORANGE (410 4110);
FORCEPROP 2 LASTPIN (400 4050) $PN 267
J 0
(410 4060);
DISPLAY 0.617021 (410 4060);
PAINT ORANGE (410 4060);
FORCEPROP 2 LASTPIN (400 4000) $PN 266
J 0
(410 4010);
DISPLAY 0.617021 (410 4010);
PAINT ORANGE (410 4010);
FORCEPROP 2 LASTPIN (400 3950) $PN 256
J 0
(410 3960);
DISPLAY 0.617021 (410 3960);
PAINT ORANGE (410 3960);
FORCEPROP 2 LASTPIN (400 3900) $PN 255
J 0
(410 3910);
DISPLAY 0.617021 (410 3910);
PAINT ORANGE (410 3910);
FORCEPROP 2 LASTPIN (400 3850) $PN 245
J 0
(410 3860);
DISPLAY 0.617021 (410 3860);
PAINT ORANGE (410 3860);
FORCEPROP 2 LASTPIN (400 3800) $PN 244
J 0
(410 3810);
DISPLAY 0.617021 (410 3810);
PAINT ORANGE (410 3810);
FORCEPROP 2 LASTPIN (400 3750) $PN 186
J 0
(410 3760);
DISPLAY 0.617021 (410 3760);
PAINT ORANGE (410 3760);
FORCEPROP 2 LASTPIN (400 3700) $PN 185
J 0
(410 3710);
DISPLAY 0.617021 (410 3710);
PAINT ORANGE (410 3710);
FORCEPROP 2 LASTPIN (400 3650) $PN 175
J 0
(410 3660);
DISPLAY 0.617021 (410 3660);
PAINT ORANGE (410 3660);
FORCEPROP 2 LASTPIN (400 3600) $PN 174
J 0
(410 3610);
DISPLAY 0.617021 (410 3610);
PAINT ORANGE (410 3610);
FORCEPROP 2 LASTPIN (400 3550) $PN 164
J 0
(410 3560);
DISPLAY 0.617021 (410 3560);
PAINT ORANGE (410 3560);
FORCEPROP 2 LASTPIN (400 3500) $PN 163
J 0
(410 3510);
DISPLAY 0.617021 (410 3510);
PAINT ORANGE (410 3510);
FORCEPROP 2 LASTPIN (400 3450) $PN 153
J 0
(410 3460);
DISPLAY 0.617021 (410 3460);
PAINT ORANGE (410 3460);
FORCEPROP 2 LASTPIN (400 3400) $PN 152
J 0
(410 3410);
DISPLAY 0.617021 (410 3410);
PAINT ORANGE (410 3410);
FORCEPROP 1 LAST PACK_TYPE PIP
J 0
(-450 5450);
PAINT SKYBLUE (-450 5450);
DISPLAY INVISIBLE (-450 5450);
FORCEPROP 2 LAST BOM_COST MEM
J 0
(-50 4300);
PAINT ORANGE (-50 4300);
DISPLAY INVISIBLE (-50 4300);
FORCEPROP 2 LAST CDS_LIB mstr_sconn
J 0
(-50 4300);
PAINT ORANGE (-50 4300);
DISPLAY INVISIBLE (-50 4300);
FORCEPROP 2 LAST SEC_TYPE PIP
J 0
(-450 5450);
DISPLAY 1.021277 (-450 5450);
PAINT ORANGE (-450 5450);
DISPLAY INVISIBLE (-450 5450);
FORCEPROP 2 LAST SEC 2
J 0
(-450 5450);
DISPLAY 0.680851 (-450 5450);
PAINT MONO (-450 5450);
DISPLAY INVISIBLE (-450 5450);
FORCEPROP 2 LAST CDS_LOCATION J1G2
J 0
(-450 5400);
DISPLAY 0.617021 (-450 5400);
PAINT AQUA (-450 5400);
DISPLAY INVISIBLE (-450 5400);
FORCEPROP 1 LAST PATH I64
J 0
(-50 5350);
PAINT GREEN (-50 5350);
DISPLAY INVISIBLE (-50 5350);
FORCEPROP 2 LAST ROOM DDR4_CH_H
J 0
(-50 4300);
PAINT ORANGE (-50 4300);
DISPLAY INVISIBLE (-50 4300);
FORCEADD TAP..6
R 2
(-1850 3900);
FORCEPROP 3 LASTPIN (-1900 3900) SIG_NAME M_H_DQ<42>
J 0
(-1890 3910);
DISPLAY 0.659574 (-1890 3910);
PAINT MONO (-1890 3910);
DISPLAY INVISIBLE (-1890 3910);
FORCEPROP 1 LASTPIN (-1900 3900) BN 42
J 2
(-1850 3910);
DISPLAY 0.617021 (-1850 3910);
PAINT PINK (-1850 3910);
FORCEPROP 2 LAST CDS_LIB mstr_standard
J 2
(-1850 3900);
DISPLAY 0.787234 (-1850 3900);
PAINT MONO (-1850 3900);
DISPLAY INVISIBLE (-1850 3900);
FORCEPROP 1 LAST BODY_TYPE PLUMBING
J 2
(-1850 3850);
DISPLAY 1.234043 (-1850 3850);
PAINT GREEN (-1850 3850);
DISPLAY INVISIBLE (-1850 3850);
FORCEPROP 1 LAST HDL_TAP TRUE
J 2
(-2175 3775);
DISPLAY 1.234043 (-2175 3775);
PAINT GREEN (-2175 3775);
DISPLAY INVISIBLE (-2175 3775);
FORCEPROP 1 LAST PATH I65
J 2
(-1850 3900);
DISPLAY 0.936170 (-1850 3900);
PAINT GREEN (-1850 3900);
DISPLAY INVISIBLE (-1850 3900);
FORCEADD TAP..6
R 2
(-1850 3850);
FORCEPROP 3 LASTPIN (-1900 3850) SIG_NAME M_H_DQ<43>
J 0
(-1890 3860);
DISPLAY 0.659574 (-1890 3860);
PAINT MONO (-1890 3860);
DISPLAY INVISIBLE (-1890 3860);
FORCEPROP 1 LASTPIN (-1900 3850) BN 43
J 2
(-1850 3860);
DISPLAY 0.617021 (-1850 3860);
PAINT PINK (-1850 3860);
FORCEPROP 2 LAST CDS_LIB mstr_standard
J 2
(-1850 3850);
DISPLAY 0.787234 (-1850 3850);
PAINT MONO (-1850 3850);
DISPLAY INVISIBLE (-1850 3850);
FORCEPROP 1 LAST BODY_TYPE PLUMBING
J 2
(-1850 3800);
DISPLAY 1.234043 (-1850 3800);
PAINT GREEN (-1850 3800);
DISPLAY INVISIBLE (-1850 3800);
FORCEPROP 1 LAST HDL_TAP TRUE
J 2
(-2175 3725);
DISPLAY 1.234043 (-2175 3725);
PAINT GREEN (-2175 3725);
DISPLAY INVISIBLE (-2175 3725);
FORCEPROP 1 LAST PATH I66
J 2
(-1850 3850);
DISPLAY 0.936170 (-1850 3850);
PAINT GREEN (-1850 3850);
DISPLAY INVISIBLE (-1850 3850);
FORCEADD TAP..6
R 2
(-1850 3800);
FORCEPROP 3 LASTPIN (-1900 3800) SIG_NAME M_H_DQ<40>
J 0
(-1890 3810);
DISPLAY 0.659574 (-1890 3810);
PAINT MONO (-1890 3810);
DISPLAY INVISIBLE (-1890 3810);
FORCEPROP 1 LASTPIN (-1900 3800) BN 40
J 2
(-1850 3810);
DISPLAY 0.617021 (-1850 3810);
PAINT PINK (-1850 3810);
FORCEPROP 2 LAST CDS_LIB mstr_standard
J 2
(-1850 3800);
DISPLAY 0.787234 (-1850 3800);
PAINT MONO (-1850 3800);
DISPLAY INVISIBLE (-1850 3800);
FORCEPROP 1 LAST BODY_TYPE PLUMBING
J 2
(-1850 3750);
DISPLAY 1.234043 (-1850 3750);
PAINT GREEN (-1850 3750);
DISPLAY INVISIBLE (-1850 3750);
FORCEPROP 1 LAST HDL_TAP TRUE
J 2
(-2175 3675);
DISPLAY 1.234043 (-2175 3675);
PAINT GREEN (-2175 3675);
DISPLAY INVISIBLE (-2175 3675);
FORCEPROP 1 LAST PATH I67
J 2
(-1850 3800);
DISPLAY 0.936170 (-1850 3800);
PAINT GREEN (-1850 3800);
DISPLAY INVISIBLE (-1850 3800);
FORCEADD TAP..6
R 2
(-1850 3950);
FORCEPROP 3 LASTPIN (-1900 3950) SIG_NAME M_H_DQ<45>
J 0
(-1890 3960);
DISPLAY 0.659574 (-1890 3960);
PAINT MONO (-1890 3960);
DISPLAY INVISIBLE (-1890 3960);
FORCEPROP 1 LASTPIN (-1900 3950) BN 45
J 2
(-1850 3960);
DISPLAY 0.617021 (-1850 3960);
PAINT PINK (-1850 3960);
FORCEPROP 2 LAST CDS_LIB mstr_standard
J 2
(-1850 3950);
DISPLAY 0.787234 (-1850 3950);
PAINT MONO (-1850 3950);
DISPLAY INVISIBLE (-1850 3950);
FORCEPROP 1 LAST BODY_TYPE PLUMBING
J 2
(-1850 3900);
DISPLAY 1.234043 (-1850 3900);
PAINT GREEN (-1850 3900);
DISPLAY INVISIBLE (-1850 3900);
FORCEPROP 1 LAST HDL_TAP TRUE
J 2
(-2175 3825);
DISPLAY 1.234043 (-2175 3825);
PAINT GREEN (-2175 3825);
DISPLAY INVISIBLE (-2175 3825);
FORCEPROP 1 LAST PATH I68
J 2
(-1850 3950);
DISPLAY 0.936170 (-1850 3950);
PAINT GREEN (-1850 3950);
DISPLAY INVISIBLE (-1850 3950);
FORCEADD TAP..6
R 2
(-1850 4000);
FORCEPROP 3 LASTPIN (-1900 4000) SIG_NAME M_H_DQ<44>
J 0
(-1890 4010);
DISPLAY 0.659574 (-1890 4010);
PAINT MONO (-1890 4010);
DISPLAY INVISIBLE (-1890 4010);
FORCEPROP 1 LASTPIN (-1900 4000) BN 44
J 2
(-1850 4010);
DISPLAY 0.617021 (-1850 4010);
PAINT PINK (-1850 4010);
FORCEPROP 2 LAST CDS_LIB mstr_standard
J 2
(-1850 4000);
DISPLAY 0.787234 (-1850 4000);
PAINT MONO (-1850 4000);
DISPLAY INVISIBLE (-1850 4000);
FORCEPROP 1 LAST BODY_TYPE PLUMBING
J 2
(-1850 3950);
DISPLAY 1.234043 (-1850 3950);
PAINT GREEN (-1850 3950);
DISPLAY INVISIBLE (-1850 3950);
FORCEPROP 1 LAST HDL_TAP TRUE
J 2
(-2175 3875);
DISPLAY 1.234043 (-2175 3875);
PAINT GREEN (-2175 3875);
DISPLAY INVISIBLE (-2175 3875);
FORCEPROP 1 LAST PATH I69
J 2
(-1850 4000);
DISPLAY 0.936170 (-1850 4000);
PAINT GREEN (-1850 4000);
DISPLAY INVISIBLE (-1850 4000);
FORCEADD TAP..6
R 2
(850 4700);
FORCEPROP 3 LASTPIN (800 4700) SIG_NAME M_H_DQS_DN<13>
J 0
(810 4710);
DISPLAY 0.659574 (810 4710);
PAINT MONO (810 4710);
DISPLAY INVISIBLE (810 4710);
FORCEPROP 1 LASTPIN (800 4700) BN 13
J 2
(850 4710);
DISPLAY 0.617021 (850 4710);
PAINT PINK (850 4710);
FORCEPROP 2 LAST CDS_LIB mstr_standard
J 0
(850 4700);
DISPLAY 0.787234 (850 4700);
PAINT MONO (850 4700);
DISPLAY INVISIBLE (850 4700);
FORCEPROP 1 LAST BODY_TYPE PLUMBING
J 2
(850 4650);
DISPLAY 1.234043 (850 4650);
PAINT GREEN (850 4650);
DISPLAY INVISIBLE (850 4650);
FORCEPROP 1 LAST HDL_TAP TRUE
J 2
(525 4575);
DISPLAY 1.234043 (525 4575);
PAINT GREEN (525 4575);
DISPLAY INVISIBLE (525 4575);
FORCEPROP 1 LAST PATH I7
J 2
(850 4700);
DISPLAY 0.936170 (850 4700);
PAINT GREEN (850 4700);
DISPLAY INVISIBLE (850 4700);
FORCEADD TAP..6
R 2
(-1850 3650);
FORCEPROP 3 LASTPIN (-1900 3650) SIG_NAME M_H_DQ<39>
J 0
(-1890 3660);
DISPLAY 0.659574 (-1890 3660);
PAINT MONO (-1890 3660);
DISPLAY INVISIBLE (-1890 3660);
FORCEPROP 1 LASTPIN (-1900 3650) BN 39
J 2
(-1850 3660);
DISPLAY 0.617021 (-1850 3660);
PAINT PINK (-1850 3660);
FORCEPROP 2 LAST CDS_LIB mstr_standard
J 2
(-1850 3650);
DISPLAY 0.787234 (-1850 3650);
PAINT MONO (-1850 3650);
DISPLAY INVISIBLE (-1850 3650);
FORCEPROP 1 LAST BODY_TYPE PLUMBING
J 2
(-1850 3600);
DISPLAY 1.234043 (-1850 3600);
PAINT GREEN (-1850 3600);
DISPLAY INVISIBLE (-1850 3600);
FORCEPROP 1 LAST HDL_TAP TRUE
J 2
(-2175 3525);
DISPLAY 1.234043 (-2175 3525);
PAINT GREEN (-2175 3525);
DISPLAY INVISIBLE (-2175 3525);
FORCEPROP 1 LAST PATH I70
J 2
(-1850 3650);
DISPLAY 0.936170 (-1850 3650);
PAINT GREEN (-1850 3650);
DISPLAY INVISIBLE (-1850 3650);
FORCEADD TAP..6
R 2
(-1850 3600);
FORCEPROP 3 LASTPIN (-1900 3600) SIG_NAME M_H_DQ<36>
J 0
(-1890 3610);
DISPLAY 0.659574 (-1890 3610);
PAINT MONO (-1890 3610);
DISPLAY INVISIBLE (-1890 3610);
FORCEPROP 1 LASTPIN (-1900 3600) BN 36
J 2
(-1850 3610);
DISPLAY 0.617021 (-1850 3610);
PAINT PINK (-1850 3610);
FORCEPROP 2 LAST CDS_LIB mstr_standard
J 2
(-1850 3600);
DISPLAY 0.787234 (-1850 3600);
PAINT MONO (-1850 3600);
DISPLAY INVISIBLE (-1850 3600);
FORCEPROP 1 LAST BODY_TYPE PLUMBING
J 2
(-1850 3550);
DISPLAY 1.234043 (-1850 3550);
PAINT GREEN (-1850 3550);
DISPLAY INVISIBLE (-1850 3550);
FORCEPROP 1 LAST HDL_TAP TRUE
J 2
(-2175 3475);
DISPLAY 1.234043 (-2175 3475);
PAINT GREEN (-2175 3475);
DISPLAY INVISIBLE (-2175 3475);
FORCEPROP 1 LAST PATH I71
J 2
(-1850 3600);
DISPLAY 0.936170 (-1850 3600);
PAINT GREEN (-1850 3600);
DISPLAY INVISIBLE (-1850 3600);
FORCEADD TAP..6
R 2
(-1850 3550);
FORCEPROP 3 LASTPIN (-1900 3550) SIG_NAME M_H_DQ<37>
J 0
(-1890 3560);
DISPLAY 0.659574 (-1890 3560);
PAINT MONO (-1890 3560);
DISPLAY INVISIBLE (-1890 3560);
FORCEPROP 1 LASTPIN (-1900 3550) BN 37
J 2
(-1850 3560);
DISPLAY 0.617021 (-1850 3560);
PAINT PINK (-1850 3560);
FORCEPROP 2 LAST CDS_LIB mstr_standard
J 2
(-1850 3550);
DISPLAY 0.787234 (-1850 3550);
PAINT MONO (-1850 3550);
DISPLAY INVISIBLE (-1850 3550);
FORCEPROP 1 LAST BODY_TYPE PLUMBING
J 2
(-1850 3500);
DISPLAY 1.234043 (-1850 3500);
PAINT GREEN (-1850 3500);
DISPLAY INVISIBLE (-1850 3500);
FORCEPROP 1 LAST HDL_TAP TRUE
J 2
(-2175 3425);
DISPLAY 1.234043 (-2175 3425);
PAINT GREEN (-2175 3425);
DISPLAY INVISIBLE (-2175 3425);
FORCEPROP 1 LAST PATH I72
J 2
(-1850 3550);
DISPLAY 0.936170 (-1850 3550);
PAINT GREEN (-1850 3550);
DISPLAY INVISIBLE (-1850 3550);
FORCEADD TAP..6
R 2
(-1850 3750);
FORCEPROP 3 LASTPIN (-1900 3750) SIG_NAME M_H_DQ<41>
J 0
(-1890 3760);
DISPLAY 0.659574 (-1890 3760);
PAINT MONO (-1890 3760);
DISPLAY INVISIBLE (-1890 3760);
FORCEPROP 1 LASTPIN (-1900 3750) BN 41
J 2
(-1850 3760);
DISPLAY 0.617021 (-1850 3760);
PAINT PINK (-1850 3760);
FORCEPROP 2 LAST CDS_LIB mstr_standard
J 2
(-1850 3750);
DISPLAY 0.787234 (-1850 3750);
PAINT MONO (-1850 3750);
DISPLAY INVISIBLE (-1850 3750);
FORCEPROP 1 LAST BODY_TYPE PLUMBING
J 2
(-1850 3700);
DISPLAY 1.234043 (-1850 3700);
PAINT GREEN (-1850 3700);
DISPLAY INVISIBLE (-1850 3700);
FORCEPROP 1 LAST HDL_TAP TRUE
J 2
(-2175 3625);
DISPLAY 1.234043 (-2175 3625);
PAINT GREEN (-2175 3625);
DISPLAY INVISIBLE (-2175 3625);
FORCEPROP 1 LAST PATH I73
J 2
(-1850 3750);
DISPLAY 0.936170 (-1850 3750);
PAINT GREEN (-1850 3750);
DISPLAY INVISIBLE (-1850 3750);
FORCEADD TAP..6
R 2
(-1850 3700);
FORCEPROP 3 LASTPIN (-1900 3700) SIG_NAME M_H_DQ<38>
J 0
(-1890 3710);
DISPLAY 0.659574 (-1890 3710);
PAINT MONO (-1890 3710);
DISPLAY INVISIBLE (-1890 3710);
FORCEPROP 1 LASTPIN (-1900 3700) BN 38
J 2
(-1850 3710);
DISPLAY 0.617021 (-1850 3710);
PAINT PINK (-1850 3710);
FORCEPROP 2 LAST CDS_LIB mstr_standard
J 2
(-1850 3700);
DISPLAY 0.787234 (-1850 3700);
PAINT MONO (-1850 3700);
DISPLAY INVISIBLE (-1850 3700);
FORCEPROP 1 LAST BODY_TYPE PLUMBING
J 2
(-1850 3650);
DISPLAY 1.234043 (-1850 3650);
PAINT GREEN (-1850 3650);
DISPLAY INVISIBLE (-1850 3650);
FORCEPROP 1 LAST HDL_TAP TRUE
J 2
(-2175 3575);
DISPLAY 1.234043 (-2175 3575);
PAINT GREEN (-2175 3575);
DISPLAY INVISIBLE (-2175 3575);
FORCEPROP 1 LAST PATH I74
J 2
(-1850 3700);
DISPLAY 0.936170 (-1850 3700);
PAINT GREEN (-1850 3700);
DISPLAY INVISIBLE (-1850 3700);
FORCEADD TAP..6
R 2
(-1850 3400);
FORCEPROP 3 LASTPIN (-1900 3400) SIG_NAME M_H_DQ<32>
J 0
(-1890 3410);
DISPLAY 0.659574 (-1890 3410);
PAINT MONO (-1890 3410);
DISPLAY INVISIBLE (-1890 3410);
FORCEPROP 1 LASTPIN (-1900 3400) BN 32
J 2
(-1850 3410);
DISPLAY 0.617021 (-1850 3410);
PAINT PINK (-1850 3410);
FORCEPROP 2 LAST CDS_LIB mstr_standard
J 2
(-1850 3400);
DISPLAY 0.787234 (-1850 3400);
PAINT MONO (-1850 3400);
DISPLAY INVISIBLE (-1850 3400);
FORCEPROP 1 LAST BODY_TYPE PLUMBING
J 2
(-1850 3350);
DISPLAY 1.234043 (-1850 3350);
PAINT GREEN (-1850 3350);
DISPLAY INVISIBLE (-1850 3350);
FORCEPROP 1 LAST HDL_TAP TRUE
J 2
(-2175 3275);
DISPLAY 1.234043 (-2175 3275);
PAINT GREEN (-2175 3275);
DISPLAY INVISIBLE (-2175 3275);
FORCEPROP 1 LAST PATH I75
J 2
(-1850 3400);
DISPLAY 0.936170 (-1850 3400);
PAINT GREEN (-1850 3400);
DISPLAY INVISIBLE (-1850 3400);
FORCEADD TAP..6
R 2
(-1850 3350);
FORCEPROP 3 LASTPIN (-1900 3350) SIG_NAME M_H_DQ<33>
J 0
(-1890 3360);
DISPLAY 0.659574 (-1890 3360);
PAINT MONO (-1890 3360);
DISPLAY INVISIBLE (-1890 3360);
FORCEPROP 1 LASTPIN (-1900 3350) BN 33
J 2
(-1850 3360);
DISPLAY 0.617021 (-1850 3360);
PAINT PINK (-1850 3360);
FORCEPROP 2 LAST CDS_LIB mstr_standard
J 2
(-1850 3350);
DISPLAY 0.787234 (-1850 3350);
PAINT MONO (-1850 3350);
DISPLAY INVISIBLE (-1850 3350);
FORCEPROP 1 LAST BODY_TYPE PLUMBING
J 2
(-1850 3300);
DISPLAY 1.234043 (-1850 3300);
PAINT GREEN (-1850 3300);
DISPLAY INVISIBLE (-1850 3300);
FORCEPROP 1 LAST HDL_TAP TRUE
J 2
(-2175 3225);
DISPLAY 1.234043 (-2175 3225);
PAINT GREEN (-2175 3225);
DISPLAY INVISIBLE (-2175 3225);
FORCEPROP 1 LAST PATH I76
J 2
(-1850 3350);
DISPLAY 0.936170 (-1850 3350);
PAINT GREEN (-1850 3350);
DISPLAY INVISIBLE (-1850 3350);
FORCEADD TAP..6
R 2
(-1850 3300);
FORCEPROP 3 LASTPIN (-1900 3300) SIG_NAME M_H_DQ<30>
J 0
(-1890 3310);
DISPLAY 0.659574 (-1890 3310);
PAINT MONO (-1890 3310);
DISPLAY INVISIBLE (-1890 3310);
FORCEPROP 1 LASTPIN (-1900 3300) BN 30
J 2
(-1850 3310);
DISPLAY 0.617021 (-1850 3310);
PAINT PINK (-1850 3310);
FORCEPROP 2 LAST CDS_LIB mstr_standard
J 2
(-1850 3300);
DISPLAY 0.787234 (-1850 3300);
PAINT MONO (-1850 3300);
DISPLAY INVISIBLE (-1850 3300);
FORCEPROP 1 LAST BODY_TYPE PLUMBING
J 2
(-1850 3250);
DISPLAY 1.234043 (-1850 3250);
PAINT GREEN (-1850 3250);
DISPLAY INVISIBLE (-1850 3250);
FORCEPROP 1 LAST HDL_TAP TRUE
J 2
(-2175 3175);
DISPLAY 1.234043 (-2175 3175);
PAINT GREEN (-2175 3175);
DISPLAY INVISIBLE (-2175 3175);
FORCEPROP 1 LAST PATH I77
J 2
(-1850 3300);
DISPLAY 0.936170 (-1850 3300);
PAINT GREEN (-1850 3300);
DISPLAY INVISIBLE (-1850 3300);
FORCEADD TAP..6
R 2
(-1850 3500);
FORCEPROP 3 LASTPIN (-1900 3500) SIG_NAME M_H_DQ<34>
J 0
(-1890 3510);
DISPLAY 0.659574 (-1890 3510);
PAINT MONO (-1890 3510);
DISPLAY INVISIBLE (-1890 3510);
FORCEPROP 1 LASTPIN (-1900 3500) BN 34
J 2
(-1850 3510);
DISPLAY 0.617021 (-1850 3510);
PAINT PINK (-1850 3510);
FORCEPROP 2 LAST CDS_LIB mstr_standard
J 2
(-1850 3500);
DISPLAY 0.787234 (-1850 3500);
PAINT MONO (-1850 3500);
DISPLAY INVISIBLE (-1850 3500);
FORCEPROP 1 LAST BODY_TYPE PLUMBING
J 2
(-1850 3450);
DISPLAY 1.234043 (-1850 3450);
PAINT GREEN (-1850 3450);
DISPLAY INVISIBLE (-1850 3450);
FORCEPROP 1 LAST HDL_TAP TRUE
J 2
(-2175 3375);
DISPLAY 1.234043 (-2175 3375);
PAINT GREEN (-2175 3375);
DISPLAY INVISIBLE (-2175 3375);
FORCEPROP 1 LAST PATH I78
J 2
(-1850 3500);
DISPLAY 0.936170 (-1850 3500);
PAINT GREEN (-1850 3500);
DISPLAY INVISIBLE (-1850 3500);
FORCEADD TAP..6
R 2
(-1850 3450);
FORCEPROP 3 LASTPIN (-1900 3450) SIG_NAME M_H_DQ<35>
J 0
(-1890 3460);
DISPLAY 0.659574 (-1890 3460);
PAINT MONO (-1890 3460);
DISPLAY INVISIBLE (-1890 3460);
FORCEPROP 1 LASTPIN (-1900 3450) BN 35
J 2
(-1850 3460);
DISPLAY 0.617021 (-1850 3460);
PAINT PINK (-1850 3460);
FORCEPROP 2 LAST CDS_LIB mstr_standard
J 2
(-1850 3450);
DISPLAY 0.787234 (-1850 3450);
PAINT MONO (-1850 3450);
DISPLAY INVISIBLE (-1850 3450);
FORCEPROP 1 LAST BODY_TYPE PLUMBING
J 2
(-1850 3400);
DISPLAY 1.234043 (-1850 3400);
PAINT GREEN (-1850 3400);
DISPLAY INVISIBLE (-1850 3400);
FORCEPROP 1 LAST HDL_TAP TRUE
J 2
(-2175 3325);
DISPLAY 1.234043 (-2175 3325);
PAINT GREEN (-2175 3325);
DISPLAY INVISIBLE (-2175 3325);
FORCEPROP 1 LAST PATH I79
J 2
(-1850 3450);
DISPLAY 0.936170 (-1850 3450);
PAINT GREEN (-1850 3450);
DISPLAY INVISIBLE (-1850 3450);
FORCEADD TAP..6
R 2
(650 5050);
FORCEPROP 3 LASTPIN (600 5050) SIG_NAME M_H_DQS_DP<16>
J 0
(610 5060);
DISPLAY 0.659574 (610 5060);
PAINT MONO (610 5060);
DISPLAY INVISIBLE (610 5060);
FORCEPROP 1 LASTPIN (600 5050) BN 16
J 2
(650 5060);
DISPLAY 0.617021 (650 5060);
PAINT PINK (650 5060);
FORCEPROP 2 LAST CDS_LIB mstr_standard
J 0
(650 5050);
DISPLAY 0.787234 (650 5050);
PAINT MONO (650 5050);
DISPLAY INVISIBLE (650 5050);
FORCEPROP 1 LAST BODY_TYPE PLUMBING
J 2
(650 5000);
DISPLAY 1.234043 (650 5000);
PAINT GREEN (650 5000);
DISPLAY INVISIBLE (650 5000);
FORCEPROP 1 LAST HDL_TAP TRUE
J 2
(325 4925);
DISPLAY 1.234043 (325 4925);
PAINT GREEN (325 4925);
DISPLAY INVISIBLE (325 4925);
FORCEPROP 1 LAST PATH I8
J 2
(650 5050);
DISPLAY 0.936170 (650 5050);
PAINT GREEN (650 5050);
DISPLAY INVISIBLE (650 5050);
FORCEADD TAP..6
R 2
(-1850 3100);
FORCEPROP 3 LASTPIN (-1900 3100) SIG_NAME M_H_DQ<26>
J 0
(-1890 3110);
DISPLAY 0.659574 (-1890 3110);
PAINT MONO (-1890 3110);
DISPLAY INVISIBLE (-1890 3110);
FORCEPROP 1 LASTPIN (-1900 3100) BN 26
J 2
(-1850 3110);
DISPLAY 0.617021 (-1850 3110);
PAINT PINK (-1850 3110);
FORCEPROP 2 LAST CDS_LIB mstr_standard
J 2
(-1850 3100);
DISPLAY 0.787234 (-1850 3100);
PAINT MONO (-1850 3100);
DISPLAY INVISIBLE (-1850 3100);
FORCEPROP 1 LAST BODY_TYPE PLUMBING
J 2
(-1850 3050);
DISPLAY 1.234043 (-1850 3050);
PAINT GREEN (-1850 3050);
DISPLAY INVISIBLE (-1850 3050);
FORCEPROP 1 LAST HDL_TAP TRUE
J 2
(-2175 2975);
DISPLAY 1.234043 (-2175 2975);
PAINT GREEN (-2175 2975);
DISPLAY INVISIBLE (-2175 2975);
FORCEPROP 1 LAST PATH I80
J 2
(-1850 3100);
DISPLAY 0.936170 (-1850 3100);
PAINT GREEN (-1850 3100);
DISPLAY INVISIBLE (-1850 3100);
FORCEADD TAP..6
R 2
(-1850 3150);
FORCEPROP 3 LASTPIN (-1900 3150) SIG_NAME M_H_DQ<29>
J 0
(-1890 3160);
DISPLAY 0.659574 (-1890 3160);
PAINT MONO (-1890 3160);
DISPLAY INVISIBLE (-1890 3160);
FORCEPROP 1 LASTPIN (-1900 3150) BN 29
J 2
(-1850 3160);
DISPLAY 0.617021 (-1850 3160);
PAINT PINK (-1850 3160);
FORCEPROP 2 LAST CDS_LIB mstr_standard
J 2
(-1850 3150);
DISPLAY 0.787234 (-1850 3150);
PAINT MONO (-1850 3150);
DISPLAY INVISIBLE (-1850 3150);
FORCEPROP 1 LAST BODY_TYPE PLUMBING
J 2
(-1850 3100);
DISPLAY 1.234043 (-1850 3100);
PAINT GREEN (-1850 3100);
DISPLAY INVISIBLE (-1850 3100);
FORCEPROP 1 LAST HDL_TAP TRUE
J 2
(-2175 3025);
DISPLAY 1.234043 (-2175 3025);
PAINT GREEN (-2175 3025);
DISPLAY INVISIBLE (-2175 3025);
FORCEPROP 1 LAST PATH I81
J 2
(-1850 3150);
DISPLAY 0.936170 (-1850 3150);
PAINT GREEN (-1850 3150);
DISPLAY INVISIBLE (-1850 3150);
FORCEADD TAP..6
R 2
(-1850 3050);
FORCEPROP 3 LASTPIN (-1900 3050) SIG_NAME M_H_DQ<27>
J 0
(-1890 3060);
DISPLAY 0.659574 (-1890 3060);
PAINT MONO (-1890 3060);
DISPLAY INVISIBLE (-1890 3060);
FORCEPROP 1 LASTPIN (-1900 3050) BN 27
J 2
(-1850 3060);
DISPLAY 0.617021 (-1850 3060);
PAINT PINK (-1850 3060);
FORCEPROP 2 LAST CDS_LIB mstr_standard
J 2
(-1850 3050);
DISPLAY 0.787234 (-1850 3050);
PAINT MONO (-1850 3050);
DISPLAY INVISIBLE (-1850 3050);
FORCEPROP 1 LAST BODY_TYPE PLUMBING
J 2
(-1850 3000);
DISPLAY 1.234043 (-1850 3000);
PAINT GREEN (-1850 3000);
DISPLAY INVISIBLE (-1850 3000);
FORCEPROP 1 LAST HDL_TAP TRUE
J 2
(-2175 2925);
DISPLAY 1.234043 (-2175 2925);
PAINT GREEN (-2175 2925);
DISPLAY INVISIBLE (-2175 2925);
FORCEPROP 1 LAST PATH I82
J 2
(-1850 3050);
DISPLAY 0.936170 (-1850 3050);
PAINT GREEN (-1850 3050);
DISPLAY INVISIBLE (-1850 3050);
FORCEADD TAP..6
R 2
(-1850 3200);
FORCEPROP 3 LASTPIN (-1900 3200) SIG_NAME M_H_DQ<28>
J 0
(-1890 3210);
DISPLAY 0.659574 (-1890 3210);
PAINT MONO (-1890 3210);
DISPLAY INVISIBLE (-1890 3210);
FORCEPROP 1 LASTPIN (-1900 3200) BN 28
J 2
(-1850 3210);
DISPLAY 0.617021 (-1850 3210);
PAINT PINK (-1850 3210);
FORCEPROP 2 LAST CDS_LIB mstr_standard
J 2
(-1850 3200);
DISPLAY 0.787234 (-1850 3200);
PAINT MONO (-1850 3200);
DISPLAY INVISIBLE (-1850 3200);
FORCEPROP 1 LAST BODY_TYPE PLUMBING
J 2
(-1850 3150);
DISPLAY 1.234043 (-1850 3150);
PAINT GREEN (-1850 3150);
DISPLAY INVISIBLE (-1850 3150);
FORCEPROP 1 LAST HDL_TAP TRUE
J 2
(-2175 3075);
DISPLAY 1.234043 (-2175 3075);
PAINT GREEN (-2175 3075);
DISPLAY INVISIBLE (-2175 3075);
FORCEPROP 1 LAST PATH I83
J 2
(-1850 3200);
DISPLAY 0.936170 (-1850 3200);
PAINT GREEN (-1850 3200);
DISPLAY INVISIBLE (-1850 3200);
FORCEADD TAP..6
R 2
(-1850 3250);
FORCEPROP 3 LASTPIN (-1900 3250) SIG_NAME M_H_DQ<31>
J 0
(-1890 3260);
DISPLAY 0.659574 (-1890 3260);
PAINT MONO (-1890 3260);
DISPLAY INVISIBLE (-1890 3260);
FORCEPROP 1 LASTPIN (-1900 3250) BN 31
J 2
(-1850 3260);
DISPLAY 0.617021 (-1850 3260);
PAINT PINK (-1850 3260);
FORCEPROP 2 LAST CDS_LIB mstr_standard
J 2
(-1850 3250);
DISPLAY 0.787234 (-1850 3250);
PAINT MONO (-1850 3250);
DISPLAY INVISIBLE (-1850 3250);
FORCEPROP 1 LAST BODY_TYPE PLUMBING
J 2
(-1850 3200);
DISPLAY 1.234043 (-1850 3200);
PAINT GREEN (-1850 3200);
DISPLAY INVISIBLE (-1850 3200);
FORCEPROP 1 LAST HDL_TAP TRUE
J 2
(-2175 3125);
DISPLAY 1.234043 (-2175 3125);
PAINT GREEN (-2175 3125);
DISPLAY INVISIBLE (-2175 3125);
FORCEPROP 1 LAST PATH I84
J 2
(-1850 3250);
DISPLAY 0.936170 (-1850 3250);
PAINT GREEN (-1850 3250);
DISPLAY INVISIBLE (-1850 3250);
FORCEADD TAP..6
R 2
(-1850 2850);
FORCEPROP 3 LASTPIN (-1900 2850) SIG_NAME M_H_DQ<23>
J 0
(-1890 2860);
DISPLAY 0.659574 (-1890 2860);
PAINT MONO (-1890 2860);
DISPLAY INVISIBLE (-1890 2860);
FORCEPROP 1 LASTPIN (-1900 2850) BN 23
J 2
(-1850 2860);
DISPLAY 0.617021 (-1850 2860);
PAINT PINK (-1850 2860);
FORCEPROP 2 LAST CDS_LIB mstr_standard
J 2
(-1850 2850);
DISPLAY 0.787234 (-1850 2850);
PAINT MONO (-1850 2850);
DISPLAY INVISIBLE (-1850 2850);
FORCEPROP 1 LAST BODY_TYPE PLUMBING
J 2
(-1850 2800);
DISPLAY 1.234043 (-1850 2800);
PAINT GREEN (-1850 2800);
DISPLAY INVISIBLE (-1850 2800);
FORCEPROP 1 LAST HDL_TAP TRUE
J 2
(-2175 2725);
DISPLAY 1.234043 (-2175 2725);
PAINT GREEN (-2175 2725);
DISPLAY INVISIBLE (-2175 2725);
FORCEPROP 1 LAST PATH I85
J 2
(-1850 2850);
DISPLAY 0.936170 (-1850 2850);
PAINT GREEN (-1850 2850);
DISPLAY INVISIBLE (-1850 2850);
FORCEADD TAP..6
R 2
(-1850 2900);
FORCEPROP 3 LASTPIN (-1900 2900) SIG_NAME M_H_DQ<22>
J 0
(-1890 2910);
DISPLAY 0.659574 (-1890 2910);
PAINT MONO (-1890 2910);
DISPLAY INVISIBLE (-1890 2910);
FORCEPROP 1 LASTPIN (-1900 2900) BN 22
J 2
(-1850 2910);
DISPLAY 0.617021 (-1850 2910);
PAINT PINK (-1850 2910);
FORCEPROP 2 LAST CDS_LIB mstr_standard
J 2
(-1850 2900);
DISPLAY 0.787234 (-1850 2900);
PAINT MONO (-1850 2900);
DISPLAY INVISIBLE (-1850 2900);
FORCEPROP 1 LAST BODY_TYPE PLUMBING
J 2
(-1850 2850);
DISPLAY 1.234043 (-1850 2850);
PAINT GREEN (-1850 2850);
DISPLAY INVISIBLE (-1850 2850);
FORCEPROP 1 LAST HDL_TAP TRUE
J 2
(-2175 2775);
DISPLAY 1.234043 (-2175 2775);
PAINT GREEN (-2175 2775);
DISPLAY INVISIBLE (-2175 2775);
FORCEPROP 1 LAST PATH I86
J 2
(-1850 2900);
DISPLAY 0.936170 (-1850 2900);
PAINT GREEN (-1850 2900);
DISPLAY INVISIBLE (-1850 2900);
FORCEADD TAP..6
R 2
(-1850 2800);
FORCEPROP 3 LASTPIN (-1900 2800) SIG_NAME M_H_DQ<20>
J 0
(-1890 2810);
DISPLAY 0.659574 (-1890 2810);
PAINT MONO (-1890 2810);
DISPLAY INVISIBLE (-1890 2810);
FORCEPROP 1 LASTPIN (-1900 2800) BN 20
J 2
(-1850 2810);
DISPLAY 0.617021 (-1850 2810);
PAINT PINK (-1850 2810);
FORCEPROP 2 LAST CDS_LIB mstr_standard
J 2
(-1850 2800);
DISPLAY 0.787234 (-1850 2800);
PAINT MONO (-1850 2800);
DISPLAY INVISIBLE (-1850 2800);
FORCEPROP 1 LAST BODY_TYPE PLUMBING
J 2
(-1850 2750);
DISPLAY 1.234043 (-1850 2750);
PAINT GREEN (-1850 2750);
DISPLAY INVISIBLE (-1850 2750);
FORCEPROP 1 LAST HDL_TAP TRUE
J 2
(-2175 2675);
DISPLAY 1.234043 (-2175 2675);
PAINT GREEN (-2175 2675);
DISPLAY INVISIBLE (-2175 2675);
FORCEPROP 1 LAST PATH I87
J 2
(-1850 2800);
DISPLAY 0.936170 (-1850 2800);
PAINT GREEN (-1850 2800);
DISPLAY INVISIBLE (-1850 2800);
FORCEADD TAP..6
R 2
(-1850 3000);
FORCEPROP 3 LASTPIN (-1900 3000) SIG_NAME M_H_DQ<24>
J 0
(-1890 3010);
DISPLAY 0.659574 (-1890 3010);
PAINT MONO (-1890 3010);
DISPLAY INVISIBLE (-1890 3010);
FORCEPROP 1 LASTPIN (-1900 3000) BN 24
J 2
(-1850 3010);
DISPLAY 0.617021 (-1850 3010);
PAINT PINK (-1850 3010);
FORCEPROP 2 LAST CDS_LIB mstr_standard
J 2
(-1850 3000);
DISPLAY 0.787234 (-1850 3000);
PAINT MONO (-1850 3000);
DISPLAY INVISIBLE (-1850 3000);
FORCEPROP 1 LAST BODY_TYPE PLUMBING
J 2
(-1850 2950);
DISPLAY 1.234043 (-1850 2950);
PAINT GREEN (-1850 2950);
DISPLAY INVISIBLE (-1850 2950);
FORCEPROP 1 LAST HDL_TAP TRUE
J 2
(-2175 2875);
DISPLAY 1.234043 (-2175 2875);
PAINT GREEN (-2175 2875);
DISPLAY INVISIBLE (-2175 2875);
FORCEPROP 1 LAST PATH I88
J 2
(-1850 3000);
DISPLAY 0.936170 (-1850 3000);
PAINT GREEN (-1850 3000);
DISPLAY INVISIBLE (-1850 3000);
FORCEADD TAP..6
R 2
(-1850 2950);
FORCEPROP 3 LASTPIN (-1900 2950) SIG_NAME M_H_DQ<25>
J 0
(-1890 2960);
DISPLAY 0.659574 (-1890 2960);
PAINT MONO (-1890 2960);
DISPLAY INVISIBLE (-1890 2960);
FORCEPROP 1 LASTPIN (-1900 2950) BN 25
J 2
(-1850 2960);
DISPLAY 0.617021 (-1850 2960);
PAINT PINK (-1850 2960);
FORCEPROP 2 LAST CDS_LIB mstr_standard
J 2
(-1850 2950);
DISPLAY 0.787234 (-1850 2950);
PAINT MONO (-1850 2950);
DISPLAY INVISIBLE (-1850 2950);
FORCEPROP 1 LAST BODY_TYPE PLUMBING
J 2
(-1850 2900);
DISPLAY 1.234043 (-1850 2900);
PAINT GREEN (-1850 2900);
DISPLAY INVISIBLE (-1850 2900);
FORCEPROP 1 LAST HDL_TAP TRUE
J 2
(-2175 2825);
DISPLAY 1.234043 (-2175 2825);
PAINT GREEN (-2175 2825);
DISPLAY INVISIBLE (-2175 2825);
FORCEPROP 1 LAST PATH I89
J 2
(-1850 2950);
DISPLAY 0.936170 (-1850 2950);
PAINT GREEN (-1850 2950);
DISPLAY INVISIBLE (-1850 2950);
FORCEADD TAP..6
R 2
(650 5150);
FORCEPROP 3 LASTPIN (600 5150) SIG_NAME M_H_DQS_DP<17>
J 0
(610 5160);
DISPLAY 0.659574 (610 5160);
PAINT MONO (610 5160);
DISPLAY INVISIBLE (610 5160);
FORCEPROP 1 LASTPIN (600 5150) BN 17
J 2
(650 5160);
DISPLAY 0.617021 (650 5160);
PAINT PINK (650 5160);
FORCEPROP 2 LAST CDS_LIB mstr_standard
J 2
(650 5150);
DISPLAY 0.787234 (650 5150);
PAINT MONO (650 5150);
DISPLAY INVISIBLE (650 5150);
FORCEPROP 1 LAST BODY_TYPE PLUMBING
J 2
(650 5100);
DISPLAY 1.234043 (650 5100);
PAINT GREEN (650 5100);
DISPLAY INVISIBLE (650 5100);
FORCEPROP 1 LAST HDL_TAP TRUE
J 2
(325 5025);
DISPLAY 1.234043 (325 5025);
PAINT GREEN (325 5025);
DISPLAY INVISIBLE (325 5025);
FORCEPROP 1 LAST PATH I9
J 2
(650 5150);
DISPLAY 0.936170 (650 5150);
PAINT GREEN (650 5150);
DISPLAY INVISIBLE (650 5150);
FORCEADD TAP..6
R 2
(-1850 2550);
FORCEPROP 3 LASTPIN (-1900 2550) SIG_NAME M_H_DQ<17>
J 0
(-1890 2560);
DISPLAY 0.659574 (-1890 2560);
PAINT MONO (-1890 2560);
DISPLAY INVISIBLE (-1890 2560);
FORCEPROP 1 LASTPIN (-1900 2550) BN 17
J 2
(-1850 2560);
DISPLAY 0.617021 (-1850 2560);
PAINT PINK (-1850 2560);
FORCEPROP 2 LAST CDS_LIB mstr_standard
J 2
(-1850 2550);
DISPLAY 0.787234 (-1850 2550);
PAINT MONO (-1850 2550);
DISPLAY INVISIBLE (-1850 2550);
FORCEPROP 1 LAST BODY_TYPE PLUMBING
J 2
(-1850 2500);
DISPLAY 1.234043 (-1850 2500);
PAINT GREEN (-1850 2500);
DISPLAY INVISIBLE (-1850 2500);
FORCEPROP 1 LAST HDL_TAP TRUE
J 2
(-2175 2425);
DISPLAY 1.234043 (-2175 2425);
PAINT GREEN (-2175 2425);
DISPLAY INVISIBLE (-2175 2425);
FORCEPROP 1 LAST PATH I90
J 2
(-1850 2550);
DISPLAY 0.936170 (-1850 2550);
PAINT GREEN (-1850 2550);
DISPLAY INVISIBLE (-1850 2550);
FORCEADD TAP..6
R 2
(-1850 2600);
FORCEPROP 3 LASTPIN (-1900 2600) SIG_NAME M_H_DQ<16>
J 0
(-1890 2610);
DISPLAY 0.659574 (-1890 2610);
PAINT MONO (-1890 2610);
DISPLAY INVISIBLE (-1890 2610);
FORCEPROP 1 LASTPIN (-1900 2600) BN 16
J 2
(-1850 2610);
DISPLAY 0.617021 (-1850 2610);
PAINT PINK (-1850 2610);
FORCEPROP 2 LAST CDS_LIB mstr_standard
J 2
(-1850 2600);
DISPLAY 0.787234 (-1850 2600);
PAINT MONO (-1850 2600);
DISPLAY INVISIBLE (-1850 2600);
FORCEPROP 1 LAST BODY_TYPE PLUMBING
J 2
(-1850 2550);
DISPLAY 1.234043 (-1850 2550);
PAINT GREEN (-1850 2550);
DISPLAY INVISIBLE (-1850 2550);
FORCEPROP 1 LAST HDL_TAP TRUE
J 2
(-2175 2475);
DISPLAY 1.234043 (-2175 2475);
PAINT GREEN (-2175 2475);
DISPLAY INVISIBLE (-2175 2475);
FORCEPROP 1 LAST PATH I91
J 2
(-1850 2600);
DISPLAY 0.936170 (-1850 2600);
PAINT GREEN (-1850 2600);
DISPLAY INVISIBLE (-1850 2600);
FORCEADD TAP..6
R 2
(-1850 2650);
FORCEPROP 3 LASTPIN (-1900 2650) SIG_NAME M_H_DQ<19>
J 0
(-1890 2660);
DISPLAY 0.659574 (-1890 2660);
PAINT MONO (-1890 2660);
DISPLAY INVISIBLE (-1890 2660);
FORCEPROP 1 LASTPIN (-1900 2650) BN 19
J 2
(-1850 2660);
DISPLAY 0.617021 (-1850 2660);
PAINT PINK (-1850 2660);
FORCEPROP 2 LAST CDS_LIB mstr_standard
J 2
(-1850 2650);
DISPLAY 0.787234 (-1850 2650);
PAINT MONO (-1850 2650);
DISPLAY INVISIBLE (-1850 2650);
FORCEPROP 1 LAST BODY_TYPE PLUMBING
J 2
(-1850 2600);
DISPLAY 1.234043 (-1850 2600);
PAINT GREEN (-1850 2600);
DISPLAY INVISIBLE (-1850 2600);
FORCEPROP 1 LAST HDL_TAP TRUE
J 2
(-2175 2525);
DISPLAY 1.234043 (-2175 2525);
PAINT GREEN (-2175 2525);
DISPLAY INVISIBLE (-2175 2525);
FORCEPROP 1 LAST PATH I92
J 2
(-1850 2650);
DISPLAY 0.936170 (-1850 2650);
PAINT GREEN (-1850 2650);
DISPLAY INVISIBLE (-1850 2650);
FORCEADD TAP..6
R 2
(-1850 2700);
FORCEPROP 3 LASTPIN (-1900 2700) SIG_NAME M_H_DQ<18>
J 0
(-1890 2710);
DISPLAY 0.659574 (-1890 2710);
PAINT MONO (-1890 2710);
DISPLAY INVISIBLE (-1890 2710);
FORCEPROP 1 LASTPIN (-1900 2700) BN 18
J 2
(-1850 2710);
DISPLAY 0.617021 (-1850 2710);
PAINT PINK (-1850 2710);
FORCEPROP 2 LAST CDS_LIB mstr_standard
J 2
(-1850 2700);
DISPLAY 0.787234 (-1850 2700);
PAINT MONO (-1850 2700);
DISPLAY INVISIBLE (-1850 2700);
FORCEPROP 1 LAST BODY_TYPE PLUMBING
J 2
(-1850 2650);
DISPLAY 1.234043 (-1850 2650);
PAINT GREEN (-1850 2650);
DISPLAY INVISIBLE (-1850 2650);
FORCEPROP 1 LAST HDL_TAP TRUE
J 2
(-2175 2575);
DISPLAY 1.234043 (-2175 2575);
PAINT GREEN (-2175 2575);
DISPLAY INVISIBLE (-2175 2575);
FORCEPROP 1 LAST PATH I93
J 2
(-1850 2700);
DISPLAY 0.936170 (-1850 2700);
PAINT GREEN (-1850 2700);
DISPLAY INVISIBLE (-1850 2700);
FORCEADD TAP..6
R 2
(-1850 2750);
FORCEPROP 3 LASTPIN (-1900 2750) SIG_NAME M_H_DQ<21>
J 0
(-1890 2760);
DISPLAY 0.659574 (-1890 2760);
PAINT MONO (-1890 2760);
DISPLAY INVISIBLE (-1890 2760);
FORCEPROP 1 LASTPIN (-1900 2750) BN 21
J 2
(-1850 2760);
DISPLAY 0.617021 (-1850 2760);
PAINT PINK (-1850 2760);
FORCEPROP 2 LAST CDS_LIB mstr_standard
J 2
(-1850 2750);
DISPLAY 0.787234 (-1850 2750);
PAINT MONO (-1850 2750);
DISPLAY INVISIBLE (-1850 2750);
FORCEPROP 1 LAST BODY_TYPE PLUMBING
J 2
(-1850 2700);
DISPLAY 1.234043 (-1850 2700);
PAINT GREEN (-1850 2700);
DISPLAY INVISIBLE (-1850 2700);
FORCEPROP 1 LAST HDL_TAP TRUE
J 2
(-2175 2625);
DISPLAY 1.234043 (-2175 2625);
PAINT GREEN (-2175 2625);
DISPLAY INVISIBLE (-2175 2625);
FORCEPROP 1 LAST PATH I94
J 2
(-1850 2750);
DISPLAY 0.936170 (-1850 2750);
PAINT GREEN (-1850 2750);
DISPLAY INVISIBLE (-1850 2750);
FORCEADD TAP..6
R 2
(-1850 2300);
FORCEPROP 3 LASTPIN (-1900 2300) SIG_NAME M_H_DQ<10>
J 0
(-1890 2310);
DISPLAY 0.659574 (-1890 2310);
PAINT MONO (-1890 2310);
DISPLAY INVISIBLE (-1890 2310);
FORCEPROP 1 LASTPIN (-1900 2300) BN 10
J 2
(-1850 2310);
DISPLAY 0.617021 (-1850 2310);
PAINT PINK (-1850 2310);
FORCEPROP 2 LAST CDS_LIB mstr_standard
J 2
(-1850 2300);
DISPLAY 0.787234 (-1850 2300);
PAINT MONO (-1850 2300);
DISPLAY INVISIBLE (-1850 2300);
FORCEPROP 1 LAST BODY_TYPE PLUMBING
J 2
(-1850 2250);
DISPLAY 1.234043 (-1850 2250);
PAINT GREEN (-1850 2250);
DISPLAY INVISIBLE (-1850 2250);
FORCEPROP 1 LAST HDL_TAP TRUE
J 2
(-2175 2175);
DISPLAY 1.234043 (-2175 2175);
PAINT GREEN (-2175 2175);
DISPLAY INVISIBLE (-2175 2175);
FORCEPROP 1 LAST PATH I95
J 2
(-1850 2300);
DISPLAY 0.936170 (-1850 2300);
PAINT GREEN (-1850 2300);
DISPLAY INVISIBLE (-1850 2300);
FORCEADD TAP..6
R 2
(-1850 2400);
FORCEPROP 3 LASTPIN (-1900 2400) SIG_NAME M_H_DQ<12>
J 0
(-1890 2410);
DISPLAY 0.659574 (-1890 2410);
PAINT MONO (-1890 2410);
DISPLAY INVISIBLE (-1890 2410);
FORCEPROP 1 LASTPIN (-1900 2400) BN 12
J 2
(-1850 2410);
DISPLAY 0.617021 (-1850 2410);
PAINT PINK (-1850 2410);
FORCEPROP 2 LAST CDS_LIB mstr_standard
J 2
(-1850 2400);
DISPLAY 0.787234 (-1850 2400);
PAINT MONO (-1850 2400);
DISPLAY INVISIBLE (-1850 2400);
FORCEPROP 1 LAST BODY_TYPE PLUMBING
J 2
(-1850 2350);
DISPLAY 1.234043 (-1850 2350);
PAINT GREEN (-1850 2350);
DISPLAY INVISIBLE (-1850 2350);
FORCEPROP 1 LAST HDL_TAP TRUE
J 2
(-2175 2275);
DISPLAY 1.234043 (-2175 2275);
PAINT GREEN (-2175 2275);
DISPLAY INVISIBLE (-2175 2275);
FORCEPROP 1 LAST PATH I96
J 2
(-1850 2400);
DISPLAY 0.936170 (-1850 2400);
PAINT GREEN (-1850 2400);
DISPLAY INVISIBLE (-1850 2400);
FORCEADD TAP..6
R 2
(-1850 2350);
FORCEPROP 3 LASTPIN (-1900 2350) SIG_NAME M_H_DQ<13>
J 0
(-1890 2360);
DISPLAY 0.659574 (-1890 2360);
PAINT MONO (-1890 2360);
DISPLAY INVISIBLE (-1890 2360);
FORCEPROP 1 LASTPIN (-1900 2350) BN 13
J 2
(-1850 2360);
DISPLAY 0.617021 (-1850 2360);
PAINT PINK (-1850 2360);
FORCEPROP 2 LAST CDS_LIB mstr_standard
J 2
(-1850 2350);
DISPLAY 0.787234 (-1850 2350);
PAINT MONO (-1850 2350);
DISPLAY INVISIBLE (-1850 2350);
FORCEPROP 1 LAST BODY_TYPE PLUMBING
J 2
(-1850 2300);
DISPLAY 1.234043 (-1850 2300);
PAINT GREEN (-1850 2300);
DISPLAY INVISIBLE (-1850 2300);
FORCEPROP 1 LAST HDL_TAP TRUE
J 2
(-2175 2225);
DISPLAY 1.234043 (-2175 2225);
PAINT GREEN (-2175 2225);
DISPLAY INVISIBLE (-2175 2225);
FORCEPROP 1 LAST PATH I97
J 2
(-1850 2350);
DISPLAY 0.936170 (-1850 2350);
PAINT GREEN (-1850 2350);
DISPLAY INVISIBLE (-1850 2350);
FORCEADD TAP..6
R 2
(-1850 2450);
FORCEPROP 3 LASTPIN (-1900 2450) SIG_NAME M_H_DQ<15>
J 0
(-1890 2460);
DISPLAY 0.659574 (-1890 2460);
PAINT MONO (-1890 2460);
DISPLAY INVISIBLE (-1890 2460);
FORCEPROP 1 LASTPIN (-1900 2450) BN 15
J 2
(-1850 2460);
DISPLAY 0.617021 (-1850 2460);
PAINT PINK (-1850 2460);
FORCEPROP 2 LAST CDS_LIB mstr_standard
J 2
(-1850 2450);
DISPLAY 0.787234 (-1850 2450);
PAINT MONO (-1850 2450);
DISPLAY INVISIBLE (-1850 2450);
FORCEPROP 1 LAST BODY_TYPE PLUMBING
J 2
(-1850 2400);
DISPLAY 1.234043 (-1850 2400);
PAINT GREEN (-1850 2400);
DISPLAY INVISIBLE (-1850 2400);
FORCEPROP 1 LAST HDL_TAP TRUE
J 2
(-2175 2325);
DISPLAY 1.234043 (-2175 2325);
PAINT GREEN (-2175 2325);
DISPLAY INVISIBLE (-2175 2325);
FORCEPROP 1 LAST PATH I98
J 2
(-1850 2450);
DISPLAY 0.936170 (-1850 2450);
PAINT GREEN (-1850 2450);
DISPLAY INVISIBLE (-1850 2450);
FORCEADD TAP..6
R 2
(-1850 2500);
FORCEPROP 3 LASTPIN (-1900 2500) SIG_NAME M_H_DQ<14>
J 0
(-1890 2510);
DISPLAY 0.659574 (-1890 2510);
PAINT MONO (-1890 2510);
DISPLAY INVISIBLE (-1890 2510);
FORCEPROP 1 LASTPIN (-1900 2500) BN 14
J 2
(-1850 2510);
DISPLAY 0.617021 (-1850 2510);
PAINT PINK (-1850 2510);
FORCEPROP 2 LAST CDS_LIB mstr_standard
J 2
(-1850 2500);
DISPLAY 0.787234 (-1850 2500);
PAINT MONO (-1850 2500);
DISPLAY INVISIBLE (-1850 2500);
FORCEPROP 1 LAST BODY_TYPE PLUMBING
J 2
(-1850 2450);
DISPLAY 1.234043 (-1850 2450);
PAINT GREEN (-1850 2450);
DISPLAY INVISIBLE (-1850 2450);
FORCEPROP 1 LAST HDL_TAP TRUE
J 2
(-2175 2375);
DISPLAY 1.234043 (-2175 2375);
PAINT GREEN (-2175 2375);
DISPLAY INVISIBLE (-2175 2375);
FORCEPROP 1 LAST PATH I99
J 2
(-1850 2500);
DISPLAY 0.936170 (-1850 2500);
PAINT GREEN (-1850 2500);
DISPLAY INVISIBLE (-1850 2500);
FORCEADD BOM_NOTE..1
(-5050 5275);
FORCEPROP 0 LAST L1 STUFF FOR SKU A & B
J 0
(-5200 5175);
DISPLAY 1.063830 (-5200 5175);
PAINT WHITE (-5200 5175);
FORCEPROP 2 LAST CDS_LIB mstr_symbols
J 0
(-5050 5275);
PAINT ORANGE (-5050 5275);
DISPLAY INVISIBLE (-5050 5275);
FORCEPROP 2 LAST BOM_COST SB
J 0
(-5200 5250);
DISPLAY 1.361702 (-5200 5250);
PAINT ORANGE (-5200 5250);
DISPLAY INVISIBLE (-5200 5250);
FORCEPROP 1 LAST COMMENT_BODY TRUE
J 0
(-5025 5375);
DISPLAY 1.319149 (-5025 5375);
PAINT ORANGE (-5025 5375);
DISPLAY INVISIBLE (-5025 5375);
FORCEPROP 2 LAST ROOM SB_HEADERS
J 0
(-5200 5250);
DISPLAY 1.361702 (-5200 5250);
PAINT ORANGE (-5200 5250);
DISPLAY INVISIBLE (-5200 5250);
FORCEADD INTEL_CORP_BPAGE..1
(2650 500);
FORCEPROP 1 LAST CDS_CON_LAST_MODIFIED Tue Dec 01 11:51:42 2015
J 0
(1225 825);
DISPLAY 0.787234 (1225 825);
PAINT ORANGE (1225 825);
DISPLAY INVISIBLE (1225 825);
FORCEPROP 1 LAST CUSTOM_TXT_CDS <CURRENT_DESIGN_SHEET> OF <TOTAL_DESIGN_SHEETS>
J 0
(2150 525);
PAINT GREEN (2150 525);
FORCEPROP 2 LAST CUSTOM_TXT_CDS <XR_PAGE_TITLE>
J 0
(-5240 5750);
DISPLAY 0.638298 (-5240 5750);
PAINT PINK (-5240 5750);
DISPLAY INVISIBLE (-5240 5750);
FORCEPROP 2 LAST CUSTOM_TXT_CDS <CON_LAST_MODIFIED>
J 0
(775 825);
DISPLAY 1.617021 (775 825);
PAINT GREEN (775 825);
FORCEPROP 1 LAST SCH_ADDRESS3 Santa Clara, CA 95052-8119
J 0
(-1325 525);
DISPLAY 0.617021 (-1325 525);
PAINT GREEN (-1325 525);
FORCEPROP 1 LAST SCH_ADDRESS2 P.O. BOX 58119
J 0
(-1325 575);
DISPLAY 0.617021 (-1325 575);
PAINT GREEN (-1325 575);
FORCEPROP 1 LAST SCH_ADDRESS1 2200 Mission College Blvd.
J 0
(-1325 625);
DISPLAY 0.617021 (-1325 625);
PAINT GREEN (-1325 625);
FORCEPROP 1 LAST SCH_TITLE CPU1 DDR4 CH H DIMM0
J 0
(-5300 550);
DISPLAY 1.212766 (-5300 550);
PAINT WHITE (-5300 550);
FORCEPROP 1 LAST SCH_NUMBER H4694802
J 0
(1350 650);
DISPLAY 1.212766 (1350 650);
PAINT YELLOW (1350 650);
FORCEPROP 1 LAST SCH_DEPT BESD
J 1
(-1800 600);
DISPLAY 1.212766 (-1800 600);
PAINT YELLOW (-1800 600);
FORCEPROP 1 LAST SCH_REV 2.420
J 0
(2400 650);
DISPLAY 0.978723 (2400 650);
PAINT YELLOW (2400 650);
FORCEPROP 2 LAST CDS_LIB mstr_symbols
J 0
(2650 500);
DISPLAY 0.787234 (2650 500);
PAINT MONO (2650 500);
DISPLAY INVISIBLE (2650 500);
FORCEPROP 2 LAST PAGE_BORDER TRUE
J 0
(-5240 5750);
DISPLAY 0.680851 (-5240 5750);
PAINT PINK (-5240 5750);
DISPLAY INVISIBLE (-5240 5750);
FORCEPROP 1 LAST COMMENT_BODY TRUE
J 0
(2660 510);
DISPLAY 0.382979 (2660 510);
PAINT GREEN (2660 510);
DISPLAY INVISIBLE (2660 510);
FORCEPROP 2 LAST CDS_XR_PAGE_TITLE CR-79 : @BASEBOARD_FAB2_LIB.BASEBOARD_FAB2(SCH_1):PAGE79
J 0
(-5240 5750);
DISPLAY 0.638298 (-5240 5750);
PAINT PINK (-5240 5750);
DISPLAY INVISIBLE (-5240 5750);
WIRE 17 -1 (700 5175)(700 5200);
WIRE 17 -1 (700 5075)(700 5175);
WIRE 17 -1 (1500 5200)(700 5200);
FORCEPROP 2 LAST SIG_NAME M_H_DQS_DP<17:0>
J 0
(925 5210);
DISPLAY 0.617021 (925 5210);
PAINT ORANGE (925 5210);
WIRE 17 -1 (900 4425)(900 4525);
WIRE 17 -1 (900 4325)(900 4425);
WIRE 17 -1 (900 4525)(900 4625);
WIRE 17 -1 (900 4625)(900 4725);
WIRE 17 -1 (900 4225)(900 4325);
WIRE 17 -1 (900 4125)(900 4225);
WIRE 17 -1 (900 4725)(900 4825);
WIRE 17 -1 (900 4825)(900 4925);
WIRE 17 -1 (900 4025)(900 4125);
WIRE 17 -1 (900 3925)(900 4025);
WIRE 17 -1 (900 4925)(900 5025);
WIRE 17 -1 (900 5025)(900 5125);
WIRE 17 -1 (900 3825)(900 3925);
WIRE 17 -1 (900 3725)(900 3825);
WIRE 17 -1 (900 5125)(900 5150);
WIRE 17 -1 (1500 5150)(900 5150);
FORCEPROP 2 LAST SIG_NAME M_H_DQS_DN<17:0>
J 0
(925 5160);
DISPLAY 0.617021 (925 5160);
PAINT ORANGE (925 5160);
WIRE 17 -1 (700 4475)(700 4575);
WIRE 17 -1 (700 4375)(700 4475);
WIRE 17 -1 (700 4575)(700 4675);
WIRE 17 -1 (700 4675)(700 4775);
WIRE 17 -1 (700 4275)(700 4375);
WIRE 17 -1 (700 4175)(700 4275);
WIRE 17 -1 (700 4775)(700 4875);
WIRE 17 -1 (700 4875)(700 4975);
WIRE 17 -1 (700 4075)(700 4175);
WIRE 17 -1 (700 3975)(700 4075);
WIRE 17 -1 (700 4975)(700 5075);
WIRE 17 -1 (700 3875)(700 3975);
WIRE 17 -1 (700 3775)(700 3875);
WIRE 17 -1 (900 3625)(900 3725);
WIRE 17 -1 (900 3525)(900 3625);
WIRE 17 -1 (900 3425)(900 3525);
WIRE 17 -1 (700 3675)(700 3775);
WIRE 17 -1 (700 3575)(700 3675);
WIRE 17 -1 (700 3475)(700 3575);
WIRE 17 -1 (-1800 4775)(-1800 4825);
WIRE 17 -1 (-1800 4725)(-1800 4775);
WIRE 17 -1 (-1800 4825)(-1800 4875);
WIRE 17 -1 (-1800 4875)(-1800 4925);
WIRE 17 -1 (-1800 4675)(-1800 4725);
WIRE 17 -1 (-1800 4625)(-1800 4675);
WIRE 17 -1 (-1800 4925)(-1800 4950);
WIRE 17 -1 (-1300 4950)(-1800 4950);
FORCEPROP 2 LAST SIG_NAME M_H_DQ<63:0>
J 0
(-1760 4960);
DISPLAY 0.617021 (-1760 4960);
PAINT ORANGE (-1760 4960);
WIRE 17 -1 (-1800 4575)(-1800 4625);
WIRE 17 -1 (-1800 4525)(-1800 4575);
WIRE 17 -1 (-1800 4475)(-1800 4525);
WIRE 17 -1 (-1800 4425)(-1800 4475);
WIRE 17 -1 (-1800 4375)(-1800 4425);
WIRE 17 -1 (-1800 4325)(-1800 4375);
WIRE 17 -1 (-1800 4275)(-1800 4325);
WIRE 17 -1 (-1800 4225)(-1800 4275);
WIRE 17 -1 (-1800 4175)(-1800 4225);
WIRE 17 -1 (-1800 4125)(-1800 4175);
WIRE 17 -1 (-1800 4075)(-1800 4125);
WIRE 17 -1 (-1800 4025)(-1800 4075);
WIRE 17 -1 (-1800 3975)(-1800 4025);
WIRE 17 -1 (-1800 3925)(-1800 3975);
WIRE 17 -1 (-1800 3875)(-1800 3925);
WIRE 17 -1 (-1800 3825)(-1800 3875);
WIRE 17 -1 (-1800 3775)(-1800 3825);
WIRE 17 -1 (-1800 3725)(-1800 3775);
WIRE 17 -1 (-1800 3675)(-1800 3725);
WIRE 17 -1 (-1800 3625)(-1800 3675);
WIRE 17 -1 (-1800 3575)(-1800 3625);
WIRE 17 -1 (-1800 3525)(-1800 3575);
WIRE 17 -1 (-1800 3475)(-1800 3525);
WIRE 17 -1 (-1800 3425)(-1800 3475);
WIRE 17 -1 (-1800 3375)(-1800 3425);
WIRE 17 -1 (-1800 3325)(-1800 3375);
WIRE 17 -1 (-1800 3275)(-1800 3325);
WIRE 17 -1 (-3400 4875)(-3400 4925);
WIRE 17 -1 (-3400 4825)(-3400 4875);
WIRE 17 -1 (-3400 4925)(-3400 4950);
WIRE 17 -1 (-3950 4950)(-3400 4950);
FORCEPROP 2 LAST SIG_NAME M_H_MA<17:0>
J 0
(-3900 4960);
DISPLAY 0.617021 (-3900 4960);
PAINT ORANGE (-3900 4960);
WIRE 17 -1 (-3400 4675)(-3400 4725);
WIRE 17 -1 (-3400 4625)(-3400 4675);
WIRE 17 -1 (-3400 4725)(-3400 4775);
WIRE 17 -1 (-3400 4775)(-3400 4825);
WIRE 17 -1 (-3400 4575)(-3400 4625);
WIRE 17 -1 (-3400 4525)(-3400 4575);
WIRE 17 -1 (-3400 4475)(-3400 4525);
WIRE 17 -1 (-3400 4425)(-3400 4475);
WIRE 17 -1 (-3400 4375)(-3400 4425);
WIRE 17 -1 (-3400 4325)(-3400 4375);
WIRE 17 -1 (-3400 4275)(-3400 4325);
WIRE 17 -1 (-3400 4225)(-3400 4275);
WIRE 17 -1 (-3400 4175)(-3400 4225);
WIRE 17 -1 (-3400 4125)(-3400 4175);
WIRE 17 -1 (-3400 4075)(-3400 4125);
WIRE 17 -1 (-1800 2725)(-1800 2775);
WIRE 17 -1 (-1800 2675)(-1800 2725);
WIRE 17 -1 (-1800 2775)(-1800 2825);
WIRE 17 -1 (-1800 2825)(-1800 2875);
WIRE 17 -1 (-1800 2625)(-1800 2675);
WIRE 17 -1 (-1800 2575)(-1800 2625);
WIRE 17 -1 (-1800 2875)(-1800 2925);
WIRE 17 -1 (-1800 2925)(-1800 2975);
WIRE 17 -1 (-1800 2525)(-1800 2575);
WIRE 17 -1 (-1800 2475)(-1800 2525);
WIRE 17 -1 (-1800 2975)(-1800 3025);
WIRE 17 -1 (-1800 3025)(-1800 3075);
WIRE 17 -1 (-1800 2425)(-1800 2475);
WIRE 17 -1 (-1800 2375)(-1800 2425);
WIRE 17 -1 (-1800 3075)(-1800 3125);
WIRE 17 -1 (-1800 3125)(-1800 3175);
WIRE 17 -1 (-1800 2325)(-1800 2375);
WIRE 17 -1 (-1800 2275)(-1800 2325);
WIRE 17 -1 (-1800 3175)(-1800 3225);
WIRE 17 -1 (-1800 3225)(-1800 3275);
WIRE 17 -1 (-1800 2225)(-1800 2275);
WIRE 17 -1 (-1800 2175)(-1800 2225);
WIRE 17 -1 (-1800 2125)(-1800 2175);
WIRE 17 -1 (-1800 2075)(-1800 2125);
WIRE 17 -1 (-1800 2025)(-1800 2075);
WIRE 17 -1 (-1800 1975)(-1800 2025);
WIRE 17 -1 (-1800 1925)(-1800 1975);
WIRE 17 -1 (-1800 1875)(-1800 1925);
WIRE 17 -1 (-1800 1825)(-1800 1875);
WIRE 17 -1 (-1800 1775)(-1800 1825);
WIRE 17 -1 (-3400 4000)(-3400 3975);
WIRE 17 -1 (-3400 4000)(-3950 4000);
FORCEPROP 2 LAST SIG_NAME M_H_BA<1:0>
J 0
(-3900 4010);
DISPLAY 0.617021 (-3900 4010);
PAINT ORANGE (-3900 4010);
WIRE 17 -1 (-3400 3900)(-3400 3875);
WIRE 17 -1 (-3400 3900)(-3950 3900);
FORCEPROP 2 LAST SIG_NAME M_H_BG<1:0>
J 0
(-3900 3910);
DISPLAY 0.617021 (-3900 3910);
PAINT ORANGE (-3900 3910);
WIRE 17 -1 (-3400 3925)(-3400 3975);
WIRE 17 -1 (-3400 3750)(-3400 3725);
WIRE 17 -1 (-3400 3750)(-3950 3750);
FORCEPROP 2 LAST SIG_NAME M_H_CLK_DP<3:0>
J 0
(-3900 3760);
DISPLAY 0.617021 (-3900 3760);
PAINT ORANGE (-3900 3760);
WIRE 17 -1 (-3400 3625)(-3400 3725);
WIRE 17 -1 (-3400 3825)(-3400 3875);
WIRE 17 -1 (-3600 3700)(-3600 3675);
WIRE 17 -1 (-3600 3700)(-3950 3700);
FORCEPROP 2 LAST SIG_NAME M_H_CLK_DN<3:0>
J 0
(-3900 3710);
DISPLAY 0.617021 (-3900 3710);
PAINT ORANGE (-3900 3710);
WIRE 17 -1 (-3400 3375)(-3400 3425);
WIRE 17 -1 (-3400 3325)(-3400 3375);
WIRE 17 -1 (-3400 3450)(-3400 3425);
WIRE 17 -1 (-3400 3450)(-3950 3450);
FORCEPROP 2 LAST SIG_NAME M_H_CS_N<7:0>
J 0
(-3925 3460);
DISPLAY 0.617021 (-3925 3460);
PAINT ORANGE (-3925 3460);
WIRE 17 -1 (-3400 3275)(-3400 3325);
WIRE 17 -1 (-3400 3200)(-3400 3175);
WIRE 17 -1 (-3400 3200)(-3950 3200);
FORCEPROP 2 LAST SIG_NAME M_H_CKE<3:0>
J 0
(-3925 3210);
DISPLAY 0.617021 (-3925 3210);
PAINT ORANGE (-3925 3210);
WIRE 17 -1 (-3400 3125)(-3400 3175);
WIRE 17 -1 (-3600 3675)(-3600 3575);
WIRE 17 -1 (-3400 2825)(-3400 2875);
WIRE 17 -1 (-3400 2775)(-3400 2825);
WIRE 17 -1 (-3400 2900)(-3400 2875);
WIRE 17 -1 (-3400 2900)(-3950 2900);
FORCEPROP 2 LAST SIG_NAME M_H_ECC<7:0>
J 0
(-3925 2910);
DISPLAY 0.617021 (-3925 2910);
PAINT ORANGE (-3925 2910);
WIRE 17 -1 (-3400 2975)(-3400 3025);
WIRE 17 -1 (-3400 3050)(-3400 3025);
WIRE 17 -1 (-3400 3050)(-3950 3050);
FORCEPROP 2 LAST SIG_NAME M_H_ODT<3:0>
J 0
(-3925 3060);
DISPLAY 0.617021 (-3925 3060);
PAINT ORANGE (-3925 3060);
WIRE 17 -1 (-3400 2725)(-3400 2775);
WIRE 17 -1 (-3400 2675)(-3400 2725);
WIRE 17 -1 (-3400 2625)(-3400 2675);
WIRE 17 -1 (-3400 2575)(-3400 2625);
WIRE 17 -1 (-3400 2525)(-3400 2575);
WIRE 16 -1 (-1150 1150)(-950 1150);
WIRE 16 -1 (-1150 1150)(-1150 1200);
WIRE 16 -1 (-1150 1200)(-950 1200);
WIRE 16 -1 (-1150 1200)(-1150 1250);
WIRE 16 -1 (-1150 1250)(-950 1250);
WIRE 16 -1 (-1150 1250)(-1150 1300);
WIRE 16 -1 (-1150 1300)(-950 1300);
WIRE 16 -1 (-1150 1300)(-1150 1350);
WIRE 16 -1 (-1150 1350)(-950 1350);
WIRE 16 -1 (-1150 1350)(-1150 1400);
WIRE 16 -1 (-1150 1400)(-950 1400);
WIRE 16 -1 (-1150 1400)(-1150 1450);
WIRE 16 -1 (-1150 1450)(-950 1450);
WIRE 16 -1 (-1150 1450)(-1150 1500);
WIRE 16 -1 (-1150 1500)(-950 1500);
WIRE 16 -1 (-1150 1500)(-1150 1550);
WIRE 16 -1 (-1150 1550)(-950 1550);
WIRE 16 -1 (-1150 1550)(-1150 1600);
WIRE 16 -1 (-1150 1600)(-950 1600);
WIRE 16 -1 (-1150 1600)(-1150 1650);
WIRE 16 -1 (-1150 1650)(-950 1650);
WIRE 16 -1 (-1150 1650)(-1150 1700);
WIRE 16 -1 (-1150 1700)(-950 1700);
WIRE 16 -1 (-1150 1700)(-1150 1750);
WIRE 16 -1 (-1150 1750)(-950 1750);
WIRE 16 -1 (-1150 1750)(-1150 1800);
WIRE 16 -1 (-1150 1800)(-950 1800);
WIRE 16 -1 (-1150 1800)(-1150 1850);
WIRE 16 -1 (-1150 1850)(-950 1850);
WIRE 16 -1 (-1150 1850)(-1150 1900);
WIRE 16 -1 (-1150 1900)(-950 1900);
WIRE 16 -1 (-1150 1900)(-1150 1950);
WIRE 16 -1 (-1150 1950)(-950 1950);
WIRE 16 -1 (-1150 1950)(-1150 2000);
WIRE 16 -1 (-1150 2000)(-1150 2050);
WIRE 16 -1 (-1150 2000)(-950 2000);
WIRE 16 -1 (-1150 2050)(-950 2050);
WIRE 16 -1 (-1150 2050)(-1150 2100);
WIRE 16 -1 (-1150 2100)(-950 2100);
WIRE 16 -1 (-1150 2100)(-1150 2150);
WIRE 16 -1 (-1150 2150)(-950 2150);
WIRE 16 -1 (-1150 2150)(-1150 2200);
WIRE 16 -1 (-1150 2200)(-950 2200);
WIRE 16 -1 (-1150 2200)(-1150 2250);
WIRE 16 -1 (-1150 2250)(-950 2250);
WIRE 16 -1 (-1150 2250)(-1150 2300);
WIRE 16 -1 (-1150 2300)(-950 2300);
WIRE 16 -1 (-1150 2300)(-1150 2350);
WIRE 16 -1 (-1150 2350)(-950 2350);
WIRE 16 -1 (-1150 2350)(-1150 2400);
WIRE 16 -1 (-1150 2400)(-950 2400);
WIRE 16 -1 (-1525 2400)(-1150 2400);
WIRE 16 -1 (-1525 2475)(-1525 2400);
WIRE 16 -1 (-1150 2500)(-950 2500);
WIRE 16 -1 (-1150 2500)(-1150 2550);
WIRE 16 -1 (-1150 2550)(-950 2550);
WIRE 16 -1 (-1300 2550)(-1150 2550);
WIRE 16 -1 (-1300 2650)(-1300 2550);
WIRE 16 -1 (2450 3500)(2450 3550);
WIRE 16 -1 (2450 3450)(2450 3500);
WIRE 16 -1 (2450 3500)(2250 3500);
WIRE 16 -1 (2450 3550)(2250 3550);
WIRE 16 -1 (2450 3400)(2450 3450);
WIRE 16 -1 (2450 3450)(2250 3450);
WIRE 16 -1 (2450 3350)(2450 3400);
WIRE 16 -1 (2450 3400)(2250 3400);
WIRE 16 -1 (2450 3300)(2450 3350);
WIRE 16 -1 (2450 3350)(2250 3350);
WIRE 16 -1 (2450 3250)(2450 3300);
WIRE 16 -1 (2450 3300)(2250 3300);
WIRE 16 -1 (2450 3200)(2450 3250);
WIRE 16 -1 (2450 3250)(2250 3250);
WIRE 16 -1 (2450 3150)(2450 3200);
WIRE 16 -1 (2450 3200)(2250 3200);
WIRE 16 -1 (2450 3100)(2450 3150);
WIRE 16 -1 (2450 3150)(2250 3150);
WIRE 16 -1 (2450 3100)(2250 3100);
WIRE 16 -1 (2450 3050)(2450 3100);
WIRE 16 -1 (2450 3000)(2450 3050);
WIRE 16 -1 (2450 3050)(2250 3050);
WIRE 16 -1 (2450 2950)(2450 3000);
WIRE 16 -1 (2450 3000)(2250 3000);
WIRE 16 -1 (2450 2900)(2450 2950);
WIRE 16 -1 (2450 2950)(2250 2950);
WIRE 16 -1 (2450 2850)(2450 2900);
WIRE 16 -1 (2450 2900)(2250 2900);
WIRE 16 -1 (2450 2800)(2450 2850);
WIRE 16 -1 (2450 2850)(2250 2850);
WIRE 16 -1 (2450 2750)(2450 2800);
WIRE 16 -1 (2450 2800)(2250 2800);
WIRE 16 -1 (2450 2700)(2450 2750);
WIRE 16 -1 (2450 2750)(2250 2750);
WIRE 16 -1 (2450 2650)(2450 2700);
WIRE 16 -1 (2450 2700)(2250 2700);
WIRE 16 -1 (2450 2600)(2450 2650);
WIRE 16 -1 (2450 2650)(2250 2650);
WIRE 16 -1 (2450 2600)(2250 2600);
WIRE 16 -1 (2450 2550)(2450 2600);
WIRE 16 -1 (2450 2500)(2450 2550);
WIRE 16 -1 (2450 2550)(2250 2550);
WIRE 16 -1 (2450 2450)(2450 2500);
WIRE 16 -1 (2450 2500)(2250 2500);
WIRE 16 -1 (2450 2400)(2450 2450);
WIRE 16 -1 (2450 2450)(2250 2450);
WIRE 16 -1 (2450 2350)(2450 2400);
WIRE 16 -1 (2450 2400)(2250 2400);
WIRE 16 -1 (2450 2300)(2450 2350);
WIRE 16 -1 (2450 2350)(2250 2350);
WIRE 16 -1 (2450 2250)(2450 2300);
WIRE 16 -1 (2450 2300)(2250 2300);
WIRE 16 -1 (2450 2200)(2450 2250);
WIRE 16 -1 (2450 2250)(2250 2250);
WIRE 16 -1 (2450 2150)(2450 2200);
WIRE 16 -1 (2450 2200)(2250 2200);
WIRE 16 -1 (2450 2100)(2450 2150);
WIRE 16 -1 (2450 2150)(2250 2150);
WIRE 16 -1 (2450 2050)(2450 2100);
WIRE 16 -1 (2450 2100)(2250 2100);
WIRE 16 -1 (2450 2050)(2250 2050);
WIRE 16 -1 (2450 2000)(2450 2050);
WIRE 16 -1 (2450 1950)(2450 2000);
WIRE 16 -1 (2450 2000)(2250 2000);
WIRE 16 -1 (2450 1900)(2450 1950);
WIRE 16 -1 (2450 1950)(2250 1950);
WIRE 16 -1 (2450 1850)(2450 1900);
WIRE 16 -1 (2450 1900)(2250 1900);
WIRE 16 -1 (2450 1800)(2450 1850);
WIRE 16 -1 (2450 1850)(2250 1850);
WIRE 16 -1 (2450 1750)(2450 1800);
WIRE 16 -1 (2450 1800)(2250 1800);
WIRE 16 -1 (2450 1700)(2450 1750);
WIRE 16 -1 (2450 1750)(2250 1750);
WIRE 16 -1 (2450 1650)(2450 1700);
WIRE 16 -1 (2450 1700)(2250 1700);
WIRE 16 -1 (2450 1600)(2450 1650);
WIRE 16 -1 (2450 1650)(2250 1650);
WIRE 16 -1 (2450 1550)(2450 1600);
WIRE 16 -1 (2450 1600)(2250 1600);
WIRE 16 -1 (2450 1550)(2250 1550);
WIRE 16 -1 (2450 1500)(2450 1550);
WIRE 16 -1 (2450 1450)(2450 1500);
WIRE 16 -1 (2450 1500)(2250 1500);
WIRE 16 -1 (2450 1400)(2450 1450);
WIRE 16 -1 (2450 1450)(2250 1450);
WIRE 16 -1 (2450 1350)(2450 1400);
WIRE 16 -1 (2450 1400)(2250 1400);
WIRE 16 -1 (2450 1300)(2450 1350);
WIRE 16 -1 (2450 1350)(2250 1350);
WIRE 16 -1 (2450 1250)(2450 1300);
WIRE 16 -1 (2450 1300)(2250 1300);
WIRE 16 -1 (2450 1150)(2450 1250);
WIRE 16 -1 (2450 1250)(2250 1250);
WIRE 16 -1 (-3100 1950)(-3525 1950);
WIRE 16 -1 (-3525 2050)(-3525 1950);
WIRE 16 -1 (-3525 2050)(-3100 2050);
WIRE 16 -1 (-5200 2050)(-3525 2050);
WIRE 16 -1 (-5200 2050)(-5200 1950);
WIRE 16 -1 (-4600 1450)(-4600 1350);
WIRE 16 -1 (-1150 2650)(-950 2650);
WIRE 16 -1 (-1150 2650)(-1150 2700);
WIRE 16 -1 (-1150 2700)(-950 2700);
WIRE 16 -1 (-1150 2700)(-1150 2750);
WIRE 16 -1 (-1150 2750)(-950 2750);
WIRE 16 -1 (-1150 2750)(-1150 2800);
WIRE 16 -1 (-1150 2800)(-950 2800);
WIRE 16 -1 (-1150 2800)(-1150 2850);
WIRE 16 -1 (-1150 2850)(-950 2850);
WIRE 16 -1 (-1150 2950)(-1150 2850);
WIRE 16 -1 (-3100 2000)(-3425 2000);
WIRE 16 -1 (-3425 2000)(-3425 2100);
WIRE 16 -1 (-3425 2100)(-3100 2100);
WIRE 16 -1 (-5200 2100)(-3425 2100);
WIRE 16 -1 (-5200 2200)(-5200 2100);
WIRE 16 -1 (50 2800)(250 2800);
WIRE 16 -1 (250 2800)(250 2850);
WIRE 16 -1 (50 2850)(250 2850);
WIRE 16 -1 (250 2850)(250 2925);
WIRE 16 -1 (1050 3550)(1250 3550);
WIRE 16 -1 (1050 3500)(1050 3550);
WIRE 16 -1 (1050 3500)(1250 3500);
WIRE 16 -1 (1050 3450)(1050 3500);
WIRE 16 -1 (1050 3450)(1250 3450);
WIRE 16 -1 (1050 3400)(1050 3450);
WIRE 16 -1 (1050 3400)(1250 3400);
WIRE 16 -1 (1050 3350)(1050 3400);
WIRE 16 -1 (1050 3350)(1250 3350);
WIRE 16 -1 (1050 3300)(1050 3350);
WIRE 16 -1 (1050 3300)(1250 3300);
WIRE 16 -1 (1050 3250)(1050 3300);
WIRE 16 -1 (1050 3250)(1250 3250);
WIRE 16 -1 (1050 3200)(1050 3250);
WIRE 16 -1 (1050 3200)(1250 3200);
WIRE 16 -1 (1050 3150)(1050 3200);
WIRE 16 -1 (1050 3150)(1250 3150);
WIRE 16 -1 (1050 3100)(1050 3150);
WIRE 16 -1 (1050 3100)(1250 3100);
WIRE 16 -1 (1050 3050)(1050 3100);
WIRE 16 -1 (1050 3050)(1250 3050);
WIRE 16 -1 (1050 3000)(1050 3050);
WIRE 16 -1 (1050 3000)(1250 3000);
WIRE 16 -1 (1050 2950)(1050 3000);
WIRE 16 -1 (1050 2950)(1250 2950);
WIRE 16 -1 (1050 2900)(1050 2950);
WIRE 16 -1 (1050 2900)(1250 2900);
WIRE 16 -1 (1050 2850)(1050 2900);
WIRE 16 -1 (1050 2850)(1250 2850);
WIRE 16 -1 (1050 2800)(1050 2850);
WIRE 16 -1 (1050 2800)(1250 2800);
WIRE 16 -1 (1050 2750)(1050 2800);
WIRE 16 -1 (1050 2750)(1250 2750);
WIRE 16 -1 (1050 2700)(1050 2750);
WIRE 16 -1 (1050 2700)(1250 2700);
WIRE 16 -1 (1050 2650)(1050 2700);
WIRE 16 -1 (1050 2650)(1250 2650);
WIRE 16 -1 (1050 2600)(1050 2650);
WIRE 16 -1 (1050 2600)(1250 2600);
WIRE 16 -1 (1050 2550)(1050 2600);
WIRE 16 -1 (1050 2550)(1250 2550);
WIRE 16 -1 (1050 2500)(1050 2550);
WIRE 16 -1 (1050 2500)(1250 2500);
WIRE 16 -1 (1050 2450)(1050 2500);
WIRE 16 -1 (1050 2450)(1250 2450);
WIRE 16 -1 (1050 2400)(1050 2450);
WIRE 16 -1 (1050 2400)(1250 2400);
WIRE 16 -1 (1050 2350)(1050 2400);
WIRE 16 -1 (1050 2350)(1250 2350);
WIRE 16 -1 (1050 2300)(1050 2350);
WIRE 16 -1 (1050 2300)(1250 2300);
WIRE 16 -1 (1050 2250)(1050 2300);
WIRE 16 -1 (1050 2250)(1250 2250);
WIRE 16 -1 (1050 2200)(1050 2250);
WIRE 16 -1 (1050 2200)(1250 2200);
WIRE 16 -1 (1050 2150)(1050 2200);
WIRE 16 -1 (1050 2150)(1250 2150);
WIRE 16 -1 (1050 2100)(1050 2150);
WIRE 16 -1 (1050 2100)(1250 2100);
WIRE 16 -1 (1050 2050)(1050 2100);
WIRE 16 -1 (1050 2050)(1250 2050);
WIRE 16 -1 (1050 2000)(1050 2050);
WIRE 16 -1 (1050 2000)(1250 2000);
WIRE 16 -1 (1050 1950)(1050 2000);
WIRE 16 -1 (1050 1950)(1250 1950);
WIRE 16 -1 (1050 1900)(1050 1950);
WIRE 16 -1 (1050 1900)(1250 1900);
WIRE 16 -1 (1050 1850)(1050 1900);
WIRE 16 -1 (1050 1850)(1250 1850);
WIRE 16 -1 (1050 1800)(1050 1850);
WIRE 16 -1 (1050 1800)(1250 1800);
WIRE 16 -1 (1050 1750)(1050 1800);
WIRE 16 -1 (1050 1750)(1250 1750);
WIRE 16 -1 (1050 1700)(1050 1750);
WIRE 16 -1 (1050 1700)(1250 1700);
WIRE 16 -1 (1050 1650)(1050 1700);
WIRE 16 -1 (1050 1650)(1250 1650);
WIRE 16 -1 (1050 1600)(1050 1650);
WIRE 16 -1 (1050 1600)(1250 1600);
WIRE 16 -1 (1050 1550)(1050 1600);
WIRE 16 -1 (1050 1550)(1250 1550);
WIRE 16 -1 (1050 1500)(1050 1550);
WIRE 16 -1 (1050 1500)(1250 1500);
WIRE 16 -1 (1050 1450)(1050 1500);
WIRE 16 -1 (1050 1450)(1250 1450);
WIRE 16 -1 (1050 1400)(1050 1450);
WIRE 16 -1 (1050 1400)(1250 1400);
WIRE 16 -1 (1050 1350)(1050 1400);
WIRE 16 -1 (1050 1350)(1250 1350);
WIRE 16 -1 (1050 1300)(1050 1350);
WIRE 16 -1 (1050 1300)(1250 1300);
WIRE 16 -1 (1050 1250)(1050 1300);
WIRE 16 -1 (1050 1250)(1250 1250);
WIRE 16 -1 (1050 1150)(1050 1250);
WIRE 16 -1 (-3100 1750)(-4600 1750);
FORCEPROP 2 LAST SIG_NAME M_H_VREF
J 0
(-3900 1760);
DISPLAY 0.617021 (-3900 1760);
PAINT ORANGE (-3900 1760);
WIRE 16 -1 (-4600 1750)(-4600 1650);
WIRE 16 -1 (-4650 1750)(-4600 1750);
WIRE 16 -1 (-3950 1600)(-3100 1600);
FORCEPROP 2 LAST SIG_NAME TP_CH_H_DIMM_H0_RFU_1
J 0
(-3900 1610);
DISPLAY 0.617021 (-3900 1610);
PAINT ORANGE (-3900 1610);
FORCEPROP 2 LASTPROP $XRERR UNIQUE?
J 0
(-4190 1600);
DISPLAY 0.638298 (-4190 1600);
PAINT MONO (-4190 1600);
DISPLAY INVISIBLE (-4190 1600);
WIRE 16 -1 (-3950 1550)(-3100 1550);
FORCEPROP 2 LAST SIG_NAME TP_CH_H_DIMM_H0_RFU_0
J 0
(-3900 1560);
DISPLAY 0.617021 (-3900 1560);
PAINT ORANGE (-3900 1560);
FORCEPROP 2 LASTPROP $XRERR UNIQUE?
J 0
(-4190 1550);
DISPLAY 0.638298 (-4190 1550);
PAINT MONO (-4190 1550);
DISPLAY INVISIBLE (-4190 1550);
WIRE 16 -1 (-3950 1650)(-3100 1650);
FORCEPROP 2 LAST SIG_NAME TP_CH_H_DIMM_H0_RFU_2
J 0
(-3900 1660);
DISPLAY 0.617021 (-3900 1660);
PAINT ORANGE (-3900 1660);
FORCEPROP 2 LASTPROP $XRERR UNIQUE?
J 0
(-4190 1650);
DISPLAY 0.638298 (-4190 1650);
PAINT MONO (-4190 1650);
DISPLAY INVISIBLE (-4190 1650);
WIRE 16 -1 (-3950 1850)(-3100 1850);
FORCEPROP 2 LAST SIG_NAME SMB_DDR_GHJ_VPP_SCL
J 0
(-3910 1860);
DISPLAY 0.617021 (-3910 1860);
PAINT ORANGE (-3910 1860);
WIRE 16 -1 (-3950 1900)(-3100 1900);
WIRE 16 -1 (-3950 1450)(-3100 1450);
FORCEPROP 2 LAST SIG_NAME FM_ADR_COMPLETE_GHJ_N
J 0
(-3900 1460);
DISPLAY 0.617021 (-3900 1460);
PAINT ORANGE (-3900 1460);
WIRE 16 -1 (-3100 2200)(-3950 2200);
FORCEPROP 2 LAST SIG_NAME M_H_ACT_N
J 0
(-3900 2210);
DISPLAY 0.617021 (-3900 2210);
PAINT ORANGE (-3900 2210);
WIRE 16 -1 (-3100 2250)(-3975 2250);
FORCEPROP 2 LAST SIG_NAME M_H_ALERT_N
J 0
(-3925 2260);
DISPLAY 0.617021 (-3925 2260);
PAINT ORANGE (-3925 2260);
WIRE 16 -1 (-3100 2500)(-3300 2500);
WIRE 16 -1 (-3100 2550)(-3300 2550);
WIRE 16 -1 (-3450 2400)(-3450 2850);
WIRE 16 -1 (-3100 2400)(-3450 2400);
WIRE 16 -1 (-3450 2850)(-3950 2850);
FORCEPROP 2 LAST SIG_NAME M_H_PAR
J 0
(-3925 2860);
DISPLAY 0.617021 (-3925 2860);
PAINT ORANGE (-3925 2860);
WIRE 16 -1 (-3550 2300)(-3550 2600);
WIRE 16 -1 (-3550 2300)(-3100 2300);
WIRE 16 -1 (-3550 2600)(-4275 2600);
FORCEPROP 2 LAST SIG_NAME FM_DIMM_EVENT_COD_N
J 0
(-4248 2614);
DISPLAY 0.617021 (-4248 2614);
PAINT ORANGE (-4248 2614);
WIRE 16 -1 (-3500 2350)(-3500 2800);
WIRE 16 -1 (-3100 2350)(-3500 2350);
WIRE 16 -1 (-3500 2800)(-3950 2800);
FORCEPROP 2 LAST SIG_NAME M_GHJ_RST_N
J 0
(-3925 2810);
DISPLAY 0.617021 (-3925 2810);
PAINT ORANGE (-3925 2810);
WIRE 16 -1 (-3100 2600)(-3300 2600);
WIRE 16 -1 (-3100 2650)(-3300 2650);
WIRE 16 -1 (-3100 2700)(-3300 2700);
WIRE 16 -1 (-3100 2750)(-3300 2750);
WIRE 16 -1 (-3100 2800)(-3300 2800);
WIRE 16 -1 (-3100 3000)(-3300 3000);
WIRE 16 -1 (-3100 2950)(-3300 2950);
WIRE 16 -1 (-3100 2850)(-3300 2850);
WIRE 16 -1 (-3100 3550)(-3500 3550);
WIRE 16 -1 (-3100 3250)(-3300 3250);
WIRE 16 -1 (-3100 3100)(-3300 3100);
WIRE 16 -1 (-3100 3150)(-3300 3150);
WIRE 16 -1 (-3100 3300)(-3300 3300);
WIRE 16 -1 (-3300 3450)(-3100 3450);
WIRE 16 -1 (-3300 3500)(-3300 3450);
WIRE 16 -1 (-3300 3500)(-3950 3500);
FORCEPROP 2 LAST SIG_NAME M_H_C<2>
J 0
(-3925 3510);
DISPLAY 0.617021 (-3925 3510);
PAINT ORANGE (-3925 3510);
WIRE 16 -1 (-3100 3400)(-3300 3400);
WIRE 16 -1 (-3100 3350)(-3300 3350);
WIRE 16 -1 (-3100 3650)(-3500 3650);
WIRE 16 -1 (-3100 3800)(-3300 3800);
WIRE 16 -1 (-3100 3600)(-3300 3600);
WIRE 16 -1 (-3100 3700)(-3300 3700);
WIRE 16 -1 (-3100 3900)(-3300 3900);
WIRE 16 -1 (-3100 3850)(-3300 3850);
WIRE 16 -1 (-3100 4050)(-3300 4050);
WIRE 16 -1 (-3100 3950)(-3300 3950);
WIRE 16 -1 (-1900 1950)(-2100 1950);
WIRE 16 -1 (-1900 1900)(-2100 1900);
WIRE 16 -1 (-1900 1850)(-2100 1850);
WIRE 16 -1 (-1900 2600)(-2100 2600);
WIRE 16 -1 (-1900 2500)(-2100 2500);
WIRE 16 -1 (-1900 3050)(-2100 3050);
WIRE 16 -1 (-1900 3100)(-2100 3100);
WIRE 16 -1 (-1900 3650)(-2100 3650);
WIRE 16 -1 (-1900 3550)(-2100 3550);
WIRE 16 -1 (-1900 3500)(-2100 3500);
WIRE 16 -1 (-1900 1750)(-2100 1750);
WIRE 16 -1 (-1900 1800)(-2100 1800);
WIRE 16 -1 (-1900 2050)(-2100 2050);
WIRE 16 -1 (-1900 2200)(-2100 2200);
WIRE 16 -1 (-1900 2300)(-2100 2300);
WIRE 16 -1 (-1900 2350)(-2100 2350);
WIRE 16 -1 (-1900 2400)(-2100 2400);
WIRE 16 -1 (-1900 2450)(-2100 2450);
WIRE 16 -1 (-1900 2550)(-2100 2550);
WIRE 16 -1 (-1900 2650)(-2100 2650);
WIRE 16 -1 (-1900 2750)(-2100 2750);
WIRE 16 -1 (-1900 2800)(-2100 2800);
WIRE 16 -1 (-1900 2850)(-2100 2850);
WIRE 16 -1 (-1900 2900)(-2100 2900);
WIRE 16 -1 (-1900 2950)(-2100 2950);
WIRE 16 -1 (-1900 3000)(-2100 3000);
WIRE 16 -1 (-1900 3250)(-2100 3250);
WIRE 16 -1 (-1900 3300)(-2100 3300);
WIRE 16 -1 (-1900 3350)(-2100 3350);
WIRE 16 -1 (-1900 3400)(-2100 3400);
WIRE 16 -1 (-1900 3450)(-2100 3450);
WIRE 16 -1 (-1900 3600)(-2100 3600);
WIRE 16 -1 (-1900 3700)(-2100 3700);
WIRE 16 -1 (-1900 3750)(-2100 3750);
WIRE 16 -1 (-1900 3800)(-2100 3800);
WIRE 16 -1 (-1900 3850)(-2100 3850);
WIRE 16 -1 (-1900 3900)(-2100 3900);
WIRE 16 -1 (-1900 3950)(-2100 3950);
WIRE 16 -1 (-1900 4000)(-2100 4000);
WIRE 16 -1 (-1900 4050)(-2100 4050);
WIRE 16 -1 (-1900 3150)(-2100 3150);
WIRE 16 -1 (-1900 3200)(-2100 3200);
WIRE 16 -1 (-1900 2000)(-2100 2000);
WIRE 16 -1 (-1900 2100)(-2100 2100);
WIRE 16 -1 (-1900 2250)(-2100 2250);
WIRE 16 -1 (-1900 2150)(-2100 2150);
WIRE 16 -1 (-1900 2700)(-2100 2700);
WIRE 16 -1 (-3100 4150)(-3300 4150);
WIRE 16 -1 (-3100 4350)(-3300 4350);
WIRE 16 -1 (-3100 4300)(-3300 4300);
WIRE 16 -1 (-3100 4250)(-3300 4250);
WIRE 16 -1 (-3100 4200)(-3300 4200);
WIRE 16 -1 (-3100 4100)(-3300 4100);
WIRE 16 -1 (-3100 4600)(-3300 4600);
WIRE 16 -1 (-3100 4550)(-3300 4550);
WIRE 16 -1 (-3100 4500)(-3300 4500);
WIRE 16 -1 (-3100 4450)(-3300 4450);
WIRE 16 -1 (-3100 4400)(-3300 4400);
WIRE 16 -1 (-3100 4850)(-3300 4850);
WIRE 16 -1 (-3100 4800)(-3300 4800);
WIRE 16 -1 (-3100 4750)(-3300 4750);
WIRE 16 -1 (-3100 4700)(-3300 4700);
WIRE 16 -1 (-3100 4650)(-3300 4650);
WIRE 16 -1 (-3100 4900)(-3300 4900);
WIRE 16 -1 (-1900 4900)(-2100 4900);
WIRE 16 -1 (-1900 4850)(-2100 4850);
WIRE 16 -1 (-1900 4800)(-2100 4800);
WIRE 16 -1 (-1900 4100)(-2100 4100);
WIRE 16 -1 (-1900 4150)(-2100 4150);
WIRE 16 -1 (-1900 4200)(-2100 4200);
WIRE 16 -1 (-1900 4250)(-2100 4250);
WIRE 16 -1 (-1900 4300)(-2100 4300);
WIRE 16 -1 (-1900 4350)(-2100 4350);
WIRE 16 -1 (-1900 4400)(-2100 4400);
WIRE 16 -1 (-1900 4450)(-2100 4450);
WIRE 16 -1 (-1900 4650)(-2100 4650);
WIRE 16 -1 (-1900 4600)(-2100 4600);
WIRE 16 -1 (-1900 4500)(-2100 4500);
WIRE 16 -1 (-1900 4550)(-2100 4550);
WIRE 16 -1 (-1900 4700)(-2100 4700);
WIRE 16 -1 (-1900 4750)(-2100 4750);
WIRE 16 -1 (600 4050)(400 4050);
WIRE 16 -1 (800 4000)(400 4000);
WIRE 16 -1 (600 3950)(400 3950);
WIRE 16 -1 (800 3900)(400 3900);
WIRE 16 -1 (600 3850)(400 3850);
WIRE 16 -1 (800 3800)(400 3800);
WIRE 16 -1 (600 3750)(400 3750);
WIRE 16 -1 (800 3700)(400 3700);
WIRE 16 -1 (600 3650)(400 3650);
WIRE 16 -1 (800 3600)(400 3600);
WIRE 16 -1 (600 3550)(400 3550);
WIRE 16 -1 (800 3500)(400 3500);
WIRE 16 -1 (600 3450)(400 3450);
WIRE 16 -1 (800 3400)(400 3400);
WIRE 16 -1 (600 4350)(400 4350);
WIRE 16 -1 (800 4300)(400 4300);
WIRE 16 -1 (600 4250)(400 4250);
WIRE 16 -1 (800 4200)(400 4200);
WIRE 16 -1 (600 4150)(400 4150);
WIRE 16 -1 (800 4100)(400 4100);
WIRE 16 -1 (800 5100)(400 5100);
WIRE 16 -1 (600 5050)(400 5050);
WIRE 16 -1 (800 5000)(400 5000);
WIRE 16 -1 (600 4950)(400 4950);
WIRE 16 -1 (800 4900)(400 4900);
WIRE 16 -1 (600 4850)(400 4850);
WIRE 16 -1 (800 4800)(400 4800);
WIRE 16 -1 (600 4750)(400 4750);
WIRE 16 -1 (800 4700)(400 4700);
WIRE 16 -1 (600 4650)(400 4650);
WIRE 16 -1 (800 4600)(400 4600);
WIRE 16 -1 (600 4550)(400 4550);
WIRE 16 -1 (800 4500)(400 4500);
WIRE 16 -1 (600 4450)(400 4450);
WIRE 16 -1 (800 4400)(400 4400);
WIRE 16 -1 (600 5150)(400 5150);
DOT 1 (-1150 2750);
DOT 1 (-1150 2150);
DOT 1 (-3525 2050);
DOT 1 (-3425 2100);
DOT 1 (-1150 2700);
DOT 1 (1050 2550);
DOT 1 (1050 2600);
DOT 1 (1050 2650);
DOT 1 (1050 2750);
DOT 1 (1050 2800);
DOT 1 (2450 1350);
DOT 1 (2450 1300);
DOT 1 (2450 1250);
DOT 1 (2450 1400);
DOT 1 (2450 1450);
DOT 1 (2450 1600);
DOT 1 (2450 1500);
DOT 1 (2450 1550);
DOT 1 (2450 1650);
DOT 1 (2450 1700);
DOT 1 (2450 1750);
DOT 1 (2450 1850);
DOT 1 (2450 1800);
DOT 1 (2450 1950);
DOT 1 (2450 1900);
DOT 1 (2450 2000);
DOT 1 (2450 2050);
DOT 1 (2450 2200);
DOT 1 (2450 2250);
DOT 1 (2450 2100);
DOT 1 (2450 2150);
DOT 1 (2450 2350);
DOT 1 (2450 2300);
DOT 1 (2450 2500);
DOT 1 (2450 2450);
DOT 1 (2450 2400);
DOT 1 (2450 2600);
DOT 1 (2450 2550);
DOT 1 (2450 2700);
DOT 1 (2450 2750);
DOT 1 (2450 2650);
DOT 1 (2450 2850);
DOT 1 (2450 2800);
DOT 1 (2450 3000);
DOT 1 (2450 2950);
DOT 1 (2450 2900);
DOT 1 (2450 3100);
DOT 1 (2450 3050);
DOT 1 (2450 3250);
DOT 1 (2450 3200);
DOT 1 (2450 3150);
DOT 1 (2450 3400);
DOT 1 (2450 3350);
DOT 1 (2450 3450);
DOT 1 (2450 3300);
DOT 1 (2450 3500);
DOT 1 (1050 3500);
DOT 1 (1050 3300);
DOT 1 (1050 3450);
DOT 1 (1050 3350);
DOT 1 (1050 3400);
DOT 1 (1050 3200);
DOT 1 (1050 3250);
DOT 1 (1050 3050);
DOT 1 (1050 3100);
DOT 1 (1050 2900);
DOT 1 (1050 2950);
DOT 1 (1050 3000);
DOT 1 (1050 2700);
DOT 1 (1050 2400);
DOT 1 (1050 2450);
DOT 1 (1050 2500);
DOT 1 (1050 2300);
DOT 1 (1050 2350);
DOT 1 (1050 2150);
DOT 1 (1050 2100);
DOT 1 (1050 2250);
DOT 1 (1050 2200);
DOT 1 (1050 2050);
DOT 1 (1050 2000);
DOT 1 (1050 1900);
DOT 1 (1050 1950);
DOT 1 (1050 1800);
DOT 1 (1050 1850);
DOT 1 (1050 1750);
DOT 1 (1050 1700);
DOT 1 (1050 1650);
DOT 1 (1050 1550);
DOT 1 (1050 1500);
DOT 1 (1050 1600);
DOT 1 (1050 1450);
DOT 1 (1050 1400);
DOT 1 (1050 1250);
DOT 1 (1050 1300);
DOT 1 (1050 1350);
DOT 1 (-4600 1750);
DOT 1 (-1150 2850);
DOT 1 (-1150 2800);
DOT 1 (-1150 2400);
DOT 1 (-1150 2300);
DOT 1 (-1150 2250);
DOT 1 (-1150 2200);
DOT 1 (-1150 2100);
DOT 1 (-1150 2050);
DOT 1 (-1150 2000);
DOT 1 (-1150 1950);
DOT 1 (-1150 1900);
DOT 1 (-1150 1850);
DOT 1 (-1150 1800);
DOT 1 (-1150 1700);
DOT 1 (-1150 1750);
DOT 1 (-1150 1650);
DOT 1 (-1150 1600);
DOT 1 (-1150 1200);
DOT 1 (-1150 1550);
DOT 1 (-1150 1500);
DOT 1 (-1150 1450);
DOT 1 (-1150 1400);
DOT 1 (-1150 1350);
DOT 1 (-1150 1300);
DOT 1 (-1150 1250);
DOT 1 (-1150 2550);
DOT 1 (-1150 2350);
DOT 1 (1050 3150);
DOT 1 (1050 2850);
DOT 1 (250 2850);
FORCENOTE
SMBUS ADDR: 0XA4
(-5275 725) 0;
DISPLAY LEFT (-5275 725);
DISPLAY 1.957447 (-5275 725);
PAINT PURPLE (-5275 725);
FORCENOTE
PLACE CAP NEAR DIMM CONNECTOR
(-5188 1127) 0;
DISPLAY LEFT (-5188 1127);
DISPLAY 1.574468 (-5188 1127);
PAINT PURPLE (-5188 1127);
QUIT
